(kicad_sch (version 20211123) (generator eeschema)

  (paper "A3")

  (title_block
    (title "SA800U (Snapdragon 845) Baseboard")
    (date "2023-10-19")
    (rev "1.0.3")
    (company "Antmicro Ltd.")
    (comment 1 "www.antmicro.com")
  )

  (junction (at 325.628 221.615) (diameter 0) (color 0 0 0 0)
  )
  (junction (at 315.849 77.216) (diameter 0) (color 0 0 0 0)
  )
  (junction (at 336.55 161.925) (diameter 0) (color 0 0 0 0)
  )
  (junction (at 336.55 186.69) (diameter 0) (color 0 0 0 0)
  )
  (junction (at 59.055 204.47) (diameter 0) (color 0 0 0 0)
  )
  (junction (at 265.43 55.88) (diameter 0) (color 0 0 0 0)
  )
  (junction (at 153.543 54.61) (diameter 0) (color 0 0 0 0)
  )
  (junction (at 255.27 68.58) (diameter 0) (color 0 0 0 0)
  )
  (junction (at 336.55 196.85) (diameter 0) (color 0 0 0 0)
  )
  (junction (at 255.27 70.104) (diameter 0) (color 0 0 0 0)
  )
  (junction (at 282.575 151.765) (diameter 0) (color 0 0 0 0)
  )
  (junction (at 115.57 161.29) (diameter 0) (color 0 0 0 0)
  )
  (junction (at 159.385 54.61) (diameter 0) (color 0 0 0 0)
  )
  (junction (at 394.335 69.215) (diameter 0) (color 0 0 0 0)
  )
  (junction (at 100.965 73.406) (diameter 0) (color 0 0 0 0)
  )
  (junction (at 280.67 226.695) (diameter 0) (color 0 0 0 0)
  )
  (junction (at 106.807 213.36) (diameter 0) (color 0 0 0 0)
  )
  (junction (at 348.869 151.765) (diameter 0) (color 0 0 0 0)
  )
  (junction (at 57.785 54.61) (diameter 0) (color 0 0 0 0)
  )
  (junction (at 285.115 77.216) (diameter 0) (color 0 0 0 0)
  )
  (junction (at 285.115 41.91) (diameter 0) (color 0 0 0 0)
  )
  (junction (at 265.43 54.61) (diameter 0) (color 0 0 0 0)
  )
  (junction (at 145.542 163.83) (diameter 0) (color 0 0 0 0)
  )
  (junction (at 290.068 226.695) (diameter 0) (color 0 0 0 0)
  )
  (junction (at 311.277 69.215) (diameter 0) (color 0 0 0 0)
  )
  (junction (at 292.735 226.695) (diameter 0) (color 0 0 0 0)
  )
  (junction (at 78.74 54.61) (diameter 0) (color 0 0 0 0)
  )
  (junction (at 347.345 151.765) (diameter 0) (color 0 0 0 0)
  )
  (junction (at 325.628 186.69) (diameter 0) (color 0 0 0 0)
  )
  (junction (at 365.76 221.615) (diameter 0) (color 0 0 0 0)
  )
  (junction (at 74.295 151.13) (diameter 0) (color 0 0 0 0)
  )
  (junction (at 59.055 96.52) (diameter 0) (color 0 0 0 0)
  )
  (junction (at 325.882 151.765) (diameter 0) (color 0 0 0 0)
  )
  (junction (at 153.543 74.93) (diameter 0) (color 0 0 0 0)
  )
  (junction (at 280.67 186.69) (diameter 0) (color 0 0 0 0)
  )
  (junction (at 135.89 161.29) (diameter 0) (color 0 0 0 0)
  )
  (junction (at 56.642 96.52) (diameter 0) (color 0 0 0 0)
  )
  (junction (at 265.43 41.91) (diameter 0) (color 0 0 0 0)
  )
  (junction (at 126.365 116.713) (diameter 0) (color 0 0 0 0)
  )
  (junction (at 364.49 79.375) (diameter 0) (color 0 0 0 0)
  )
  (junction (at 126.238 142.24) (diameter 0) (color 0 0 0 0)
  )
  (junction (at 185.928 54.61) (diameter 0) (color 0 0 0 0)
  )
  (junction (at 394.335 41.91) (diameter 0) (color 0 0 0 0)
  )
  (junction (at 66.675 74.93) (diameter 0) (color 0 0 0 0)
  )
  (junction (at 126.238 158.75) (diameter 0) (color 0 0 0 0)
  )
  (junction (at 255.27 41.91) (diameter 0) (color 0 0 0 0)
  )
  (junction (at 173.355 54.61) (diameter 0) (color 0 0 0 0)
  )
  (junction (at 280.67 151.765) (diameter 0) (color 0 0 0 0)
  )
  (junction (at 348.996 186.69) (diameter 0) (color 0 0 0 0)
  )
  (junction (at 155.067 54.61) (diameter 0) (color 0 0 0 0)
  )
  (junction (at 74.295 54.61) (diameter 0) (color 0 0 0 0)
  )
  (junction (at 347.345 186.69) (diameter 0) (color 0 0 0 0)
  )
  (junction (at 282.067 221.615) (diameter 0) (color 0 0 0 0)
  )
  (junction (at 113.665 93.345) (diameter 0) (color 0 0 0 0)
  )
  (junction (at 361.315 221.615) (diameter 0) (color 0 0 0 0)
  )
  (junction (at 113.665 118.11) (diameter 0) (color 0 0 0 0)
  )
  (junction (at 74.295 142.24) (diameter 0) (color 0 0 0 0)
  )
  (junction (at 59.055 195.58) (diameter 0) (color 0 0 0 0)
  )
  (junction (at 113.665 115.443) (diameter 0) (color 0 0 0 0)
  )
  (junction (at 145.542 142.24) (diameter 0) (color 0 0 0 0)
  )
  (junction (at 366.395 151.765) (diameter 0) (color 0 0 0 0)
  )
  (junction (at 100.965 115.57) (diameter 0) (color 0 0 0 0)
  )
  (junction (at 74.295 160.02) (diameter 0) (color 0 0 0 0)
  )
  (junction (at 282.194 186.69) (diameter 0) (color 0 0 0 0)
  )
  (junction (at 285.623 151.765) (diameter 0) (color 0 0 0 0)
  )
  (junction (at 100.965 118.11) (diameter 0) (color 0 0 0 0)
  )
  (junction (at 57.531 74.93) (diameter 0) (color 0 0 0 0)
  )
  (junction (at 361.95 151.765) (diameter 0) (color 0 0 0 0)
  )
  (junction (at 59.055 213.36) (diameter 0) (color 0 0 0 0)
  )
  (junction (at 336.55 221.615) (diameter 0) (color 0 0 0 0)
  )
  (junction (at 364.49 69.215) (diameter 0) (color 0 0 0 0)
  )
  (junction (at 107.95 158.75) (diameter 0) (color 0 0 0 0)
  )
  (junction (at 123.19 163.83) (diameter 0) (color 0 0 0 0)
  )
  (junction (at 280.67 191.77) (diameter 0) (color 0 0 0 0)
  )
  (junction (at 336.55 151.765) (diameter 0) (color 0 0 0 0)
  )
  (junction (at 347.345 221.615) (diameter 0) (color 0 0 0 0)
  )
  (junction (at 36.195 54.61) (diameter 0) (color 0 0 0 0)
  )
  (junction (at 292.862 156.845) (diameter 0) (color 0 0 0 0)
  )
  (junction (at 361.315 186.69) (diameter 0) (color 0 0 0 0)
  )
  (junction (at 302.26 53.975) (diameter 0) (color 0 0 0 0)
  )
  (junction (at 135.89 142.24) (diameter 0) (color 0 0 0 0)
  )
  (junction (at 69.215 54.61) (diameter 0) (color 0 0 0 0)
  )
  (junction (at 66.675 168.91) (diameter 0) (color 0 0 0 0)
  )
  (junction (at 318.135 74.295) (diameter 0) (color 0 0 0 0)
  )
  (junction (at 291.973 191.77) (diameter 0) (color 0 0 0 0)
  )
  (junction (at 66.675 186.69) (diameter 0) (color 0 0 0 0)
  )
  (junction (at 308.61 69.215) (diameter 0) (color 0 0 0 0)
  )
  (junction (at 336.55 231.775) (diameter 0) (color 0 0 0 0)
  )
  (junction (at 153.543 96.52) (diameter 0) (color 0 0 0 0)
  )
  (junction (at 371.094 69.215) (diameter 0) (color 0 0 0 0)
  )
  (junction (at 66.675 177.8) (diameter 0) (color 0 0 0 0)
  )
  (junction (at 365.76 186.69) (diameter 0) (color 0 0 0 0)
  )
  (junction (at 308.61 41.91) (diameter 0) (color 0 0 0 0)
  )
  (junction (at 66.675 222.25) (diameter 0) (color 0 0 0 0)
  )
  (junction (at 316.357 69.215) (diameter 0) (color 0 0 0 0)
  )
  (junction (at 348.869 221.615) (diameter 0) (color 0 0 0 0)
  )
  (junction (at 389.89 69.215) (diameter 0) (color 0 0 0 0)
  )
  (junction (at 285.115 65.405) (diameter 0) (color 0 0 0 0)
  )
  (junction (at 280.67 221.615) (diameter 0) (color 0 0 0 0)
  )
  (junction (at 126.365 118.11) (diameter 0) (color 0 0 0 0)
  )
  (junction (at 375.285 69.215) (diameter 0) (color 0 0 0 0)
  )
  (junction (at 353.441 69.215) (diameter 0) (color 0 0 0 0)
  )
  (junction (at 126.365 115.062) (diameter 0) (color 0 0 0 0)
  )
  (junction (at 290.322 191.77) (diameter 0) (color 0 0 0 0)
  )

  (no_connect (at 106.045 194.31))
  (no_connect (at 106.045 199.39))
  (no_connect (at 106.045 201.93))

  (wire (pts (xy 308.61 69.215) (xy 311.277 69.215))
    (stroke (width 0) (type default) (color 0 0 0 0))
  )
  (wire (pts (xy 371.094 69.215) (xy 375.285 69.215))
    (stroke (width 0) (type default) (color 0 0 0 0))
  )
  (wire (pts (xy 74.295 166.751) (xy 74.295 222.25))
    (stroke (width 0) (type default) (color 0 0 0 0))
  )
  (wire (pts (xy 375.285 69.215) (xy 375.285 70.485))
    (stroke (width 0) (type default) (color 0 0 0 0))
  )
  (wire (pts (xy 274.32 229.997) (xy 292.735 229.997))
    (stroke (width 0) (type default) (color 0 0 0 0))
  )
  (wire (pts (xy 123.19 163.83) (xy 145.542 163.83))
    (stroke (width 0) (type default) (color 0 0 0 0))
  )
  (wire (pts (xy 135.89 161.29) (xy 160.655 161.29))
    (stroke (width 0) (type default) (color 0 0 0 0))
  )
  (wire (pts (xy 126.365 115.062) (xy 135.255 115.062))
    (stroke (width 0) (type default) (color 0 0 0 0))
  )
  (wire (pts (xy 66.675 170.561) (xy 66.675 168.91))
    (stroke (width 0) (type default) (color 0 0 0 0))
  )
  (wire (pts (xy 348.996 186.69) (xy 361.315 186.69))
    (stroke (width 0) (type default) (color 0 0 0 0))
  )
  (wire (pts (xy 153.543 54.61) (xy 153.543 74.93))
    (stroke (width 0) (type default) (color 0 0 0 0))
  )
  (wire (pts (xy 145.542 152.654) (xy 145.542 163.83))
    (stroke (width 0) (type default) (color 0 0 0 0))
  )
  (wire (pts (xy 282.067 221.615) (xy 294.64 221.615))
    (stroke (width 0) (type default) (color 0 0 0 0))
  )
  (wire (pts (xy 255.27 81.407) (xy 255.27 84.455))
    (stroke (width 0) (type default) (color 0 0 0 0))
  )
  (wire (pts (xy 100.965 72.39) (xy 100.965 73.406))
    (stroke (width 0) (type default) (color 0 0 0 0))
  )
  (wire (pts (xy 278.765 221.615) (xy 280.67 221.615))
    (stroke (width 0) (type default) (color 0 0 0 0))
  )
  (wire (pts (xy 69.215 55.88) (xy 69.215 54.61))
    (stroke (width 0) (type default) (color 0 0 0 0))
  )
  (wire (pts (xy 285.115 77.216) (xy 285.115 78.613))
    (stroke (width 0) (type default) (color 0 0 0 0))
  )
  (wire (pts (xy 106.045 181.61) (xy 111.125 181.61))
    (stroke (width 0) (type default) (color 0 0 0 0))
  )
  (polyline (pts (xy 215.9 107.95) (xy 215.9 25.4))
    (stroke (width 0) (type default) (color 0 0 0 0))
  )

  (wire (pts (xy 74.295 160.02) (xy 80.645 160.02))
    (stroke (width 0) (type default) (color 0 0 0 0))
  )
  (wire (pts (xy 336.55 186.69) (xy 336.55 187.96))
    (stroke (width 0) (type default) (color 0 0 0 0))
  )
  (wire (pts (xy 69.215 54.61) (xy 74.295 54.61))
    (stroke (width 0) (type default) (color 0 0 0 0))
  )
  (wire (pts (xy 57.531 74.93) (xy 66.675 74.93))
    (stroke (width 0) (type default) (color 0 0 0 0))
  )
  (wire (pts (xy 59.055 202.311) (xy 59.055 204.47))
    (stroke (width 0) (type default) (color 0 0 0 0))
  )
  (wire (pts (xy 104.775 54.61) (xy 104.775 58.42))
    (stroke (width 0) (type default) (color 0 0 0 0))
  )
  (wire (pts (xy 168.275 246.38) (xy 170.815 246.38))
    (stroke (width 0) (type default) (color 0 0 0 0))
  )
  (wire (pts (xy 314.96 226.695) (xy 316.23 226.695))
    (stroke (width 0) (type default) (color 0 0 0 0))
  )
  (wire (pts (xy 33.782 57.15) (xy 31.242 57.15))
    (stroke (width 0) (type default) (color 0 0 0 0))
  )
  (wire (pts (xy 59.055 213.36) (xy 80.645 213.36))
    (stroke (width 0) (type default) (color 0 0 0 0))
  )
  (wire (pts (xy 169.545 251.46) (xy 150.495 251.46))
    (stroke (width 0) (type default) (color 0 0 0 0))
  )
  (wire (pts (xy 100.965 73.406) (xy 100.965 115.57))
    (stroke (width 0) (type default) (color 0 0 0 0))
  )
  (polyline (pts (xy 406.4 120.65) (xy 215.9 120.65))
    (stroke (width 0) (type default) (color 0 0 0 0))
  )

  (wire (pts (xy 280.67 151.765) (xy 282.575 151.765))
    (stroke (width 0) (type default) (color 0 0 0 0))
  )
  (wire (pts (xy 348.996 185.674) (xy 348.996 186.69))
    (stroke (width 0) (type default) (color 0 0 0 0))
  )
  (wire (pts (xy 106.045 210.82) (xy 106.807 210.82))
    (stroke (width 0) (type default) (color 0 0 0 0))
  )
  (wire (pts (xy 66.675 222.25) (xy 59.055 222.25))
    (stroke (width 0) (type default) (color 0 0 0 0))
  )
  (wire (pts (xy 106.045 158.75) (xy 107.95 158.75))
    (stroke (width 0) (type default) (color 0 0 0 0))
  )
  (wire (pts (xy 311.277 69.215) (xy 316.357 69.215))
    (stroke (width 0) (type default) (color 0 0 0 0))
  )
  (wire (pts (xy 66.675 186.69) (xy 80.645 186.69))
    (stroke (width 0) (type default) (color 0 0 0 0))
  )
  (wire (pts (xy 286.385 156.845) (xy 285.623 156.845))
    (stroke (width 0) (type default) (color 0 0 0 0))
  )
  (polyline (pts (xy 215.9 279.4) (xy 215.9 120.65))
    (stroke (width 0) (type default) (color 0 0 0 0))
  )

  (wire (pts (xy 315.849 77.216) (xy 315.849 78.486))
    (stroke (width 0) (type default) (color 0 0 0 0))
  )
  (wire (pts (xy 173.355 54.61) (xy 185.928 54.61))
    (stroke (width 0) (type default) (color 0 0 0 0))
  )
  (wire (pts (xy 284.226 226.695) (xy 280.67 226.695))
    (stroke (width 0) (type default) (color 0 0 0 0))
  )
  (wire (pts (xy 57.531 73.66) (xy 57.531 74.93))
    (stroke (width 0) (type default) (color 0 0 0 0))
  )
  (wire (pts (xy 139.065 96.52) (xy 153.543 96.52))
    (stroke (width 0) (type default) (color 0 0 0 0))
  )
  (wire (pts (xy 361.315 186.69) (xy 365.76 186.69))
    (stroke (width 0) (type default) (color 0 0 0 0))
  )
  (wire (pts (xy 104.775 118.11) (xy 100.965 118.11))
    (stroke (width 0) (type default) (color 0 0 0 0))
  )
  (wire (pts (xy 282.575 150.876) (xy 282.575 151.765))
    (stroke (width 0) (type default) (color 0 0 0 0))
  )
  (wire (pts (xy 99.695 58.42) (xy 99.695 52.451))
    (stroke (width 0) (type default) (color 0 0 0 0))
  )
  (wire (pts (xy 66.675 186.69) (xy 66.675 184.531))
    (stroke (width 0) (type default) (color 0 0 0 0))
  )
  (wire (pts (xy 316.357 69.215) (xy 322.58 69.215))
    (stroke (width 0) (type default) (color 0 0 0 0))
  )
  (wire (pts (xy 113.665 118.11) (xy 113.665 132.08))
    (stroke (width 0) (type default) (color 0 0 0 0))
  )
  (wire (pts (xy 237.49 92.71) (xy 222.25 92.71))
    (stroke (width 0) (type default) (color 0 0 0 0))
  )
  (wire (pts (xy 321.31 191.77) (xy 325.628 191.77))
    (stroke (width 0) (type default) (color 0 0 0 0))
  )
  (wire (pts (xy 125.095 100.33) (xy 125.095 95.123))
    (stroke (width 0) (type default) (color 0 0 0 0))
  )
  (wire (pts (xy 389.89 69.215) (xy 394.335 69.215))
    (stroke (width 0) (type default) (color 0 0 0 0))
  )
  (wire (pts (xy 59.055 96.52) (xy 130.175 96.52))
    (stroke (width 0) (type default) (color 0 0 0 0))
  )
  (wire (pts (xy 95.25 245.745) (xy 96.52 245.745))
    (stroke (width 0) (type default) (color 0 0 0 0))
  )
  (wire (pts (xy 106.045 213.36) (xy 106.807 213.36))
    (stroke (width 0) (type default) (color 0 0 0 0))
  )
  (wire (pts (xy 175.895 246.38) (xy 177.165 246.38))
    (stroke (width 0) (type default) (color 0 0 0 0))
  )
  (wire (pts (xy 336.55 161.925) (xy 336.55 165.735))
    (stroke (width 0) (type default) (color 0 0 0 0))
  )
  (wire (pts (xy 314.96 151.765) (xy 325.882 151.765))
    (stroke (width 0) (type default) (color 0 0 0 0))
  )
  (wire (pts (xy 265.43 54.61) (xy 265.43 55.88))
    (stroke (width 0) (type default) (color 0 0 0 0))
  )
  (wire (pts (xy 113.665 54.61) (xy 153.543 54.61))
    (stroke (width 0) (type default) (color 0 0 0 0))
  )
  (wire (pts (xy 66.675 168.91) (xy 80.645 168.91))
    (stroke (width 0) (type default) (color 0 0 0 0))
  )
  (wire (pts (xy 28.575 96.52) (xy 56.642 96.52))
    (stroke (width 0) (type default) (color 0 0 0 0))
  )
  (wire (pts (xy 292.862 156.845) (xy 294.64 156.845))
    (stroke (width 0) (type default) (color 0 0 0 0))
  )
  (wire (pts (xy 66.675 222.25) (xy 66.675 223.52))
    (stroke (width 0) (type default) (color 0 0 0 0))
  )
  (wire (pts (xy 314.96 231.775) (xy 336.55 231.775))
    (stroke (width 0) (type default) (color 0 0 0 0))
  )
  (wire (pts (xy 28.575 74.93) (xy 57.531 74.93))
    (stroke (width 0) (type default) (color 0 0 0 0))
  )
  (wire (pts (xy 271.145 194.31) (xy 259.715 194.31))
    (stroke (width 0) (type default) (color 0 0 0 0))
  )
  (polyline (pts (xy 13.335 25.4) (xy 203.2 25.4))
    (stroke (width 0) (type default) (color 0 0 0 0))
  )

  (wire (pts (xy 145.542 147.574) (xy 145.542 142.24))
    (stroke (width 0) (type default) (color 0 0 0 0))
  )
  (wire (pts (xy 283.972 191.77) (xy 280.67 191.77))
    (stroke (width 0) (type default) (color 0 0 0 0))
  )
  (wire (pts (xy 121.285 78.74) (xy 121.285 73.533))
    (stroke (width 0) (type default) (color 0 0 0 0))
  )
  (wire (pts (xy 293.37 196.85) (xy 293.37 202.565))
    (stroke (width 0) (type default) (color 0 0 0 0))
  )
  (wire (pts (xy 316.357 68.199) (xy 316.357 69.215))
    (stroke (width 0) (type default) (color 0 0 0 0))
  )
  (wire (pts (xy 336.55 231.775) (xy 336.55 228.6))
    (stroke (width 0) (type default) (color 0 0 0 0))
  )
  (wire (pts (xy 109.22 196.85) (xy 109.22 200.66))
    (stroke (width 0) (type default) (color 0 0 0 0))
  )
  (wire (pts (xy 159.385 54.61) (xy 173.355 54.61))
    (stroke (width 0) (type default) (color 0 0 0 0))
  )
  (wire (pts (xy 155.067 53.086) (xy 155.067 54.61))
    (stroke (width 0) (type default) (color 0 0 0 0))
  )
  (wire (pts (xy 100.965 73.406) (xy 109.855 73.406))
    (stroke (width 0) (type default) (color 0 0 0 0))
  )
  (wire (pts (xy 320.04 79.375) (xy 320.04 85.09))
    (stroke (width 0) (type default) (color 0 0 0 0))
  )
  (wire (pts (xy 314.96 161.925) (xy 336.55 161.925))
    (stroke (width 0) (type default) (color 0 0 0 0))
  )
  (wire (pts (xy 123.19 154.94) (xy 123.19 163.83))
    (stroke (width 0) (type default) (color 0 0 0 0))
  )
  (wire (pts (xy 74.295 161.671) (xy 74.295 160.02))
    (stroke (width 0) (type default) (color 0 0 0 0))
  )
  (wire (pts (xy 336.55 196.85) (xy 336.55 198.12))
    (stroke (width 0) (type default) (color 0 0 0 0))
  )
  (wire (pts (xy 336.55 161.925) (xy 336.55 158.115))
    (stroke (width 0) (type default) (color 0 0 0 0))
  )
  (wire (pts (xy 111.887 115.443) (xy 113.665 115.443))
    (stroke (width 0) (type default) (color 0 0 0 0))
  )
  (wire (pts (xy 282.575 151.765) (xy 285.623 151.765))
    (stroke (width 0) (type default) (color 0 0 0 0))
  )
  (wire (pts (xy 280.67 186.69) (xy 282.194 186.69))
    (stroke (width 0) (type default) (color 0 0 0 0))
  )
  (wire (pts (xy 59.055 222.25) (xy 59.055 220.091))
    (stroke (width 0) (type default) (color 0 0 0 0))
  )
  (wire (pts (xy 318.135 74.295) (xy 318.135 77.216))
    (stroke (width 0) (type default) (color 0 0 0 0))
  )
  (wire (pts (xy 329.565 48.26) (xy 329.565 53.975))
    (stroke (width 0) (type default) (color 0 0 0 0))
  )
  (wire (pts (xy 325.628 226.695) (xy 325.628 221.615))
    (stroke (width 0) (type default) (color 0 0 0 0))
  )
  (wire (pts (xy 135.89 147.574) (xy 135.89 142.24))
    (stroke (width 0) (type default) (color 0 0 0 0))
  )
  (wire (pts (xy 106.807 210.82) (xy 106.807 213.36))
    (stroke (width 0) (type default) (color 0 0 0 0))
  )
  (wire (pts (xy 337.185 41.91) (xy 394.335 41.91))
    (stroke (width 0) (type default) (color 0 0 0 0))
  )
  (wire (pts (xy 289.306 226.695) (xy 290.068 226.695))
    (stroke (width 0) (type default) (color 0 0 0 0))
  )
  (wire (pts (xy 106.807 213.36) (xy 106.807 215.9))
    (stroke (width 0) (type default) (color 0 0 0 0))
  )
  (wire (pts (xy 106.045 142.24) (xy 126.238 142.24))
    (stroke (width 0) (type default) (color 0 0 0 0))
  )
  (wire (pts (xy 255.27 41.91) (xy 255.27 45.085))
    (stroke (width 0) (type default) (color 0 0 0 0))
  )
  (wire (pts (xy 282.194 185.547) (xy 282.194 186.69))
    (stroke (width 0) (type default) (color 0 0 0 0))
  )
  (wire (pts (xy 280.67 221.615) (xy 280.67 226.695))
    (stroke (width 0) (type default) (color 0 0 0 0))
  )
  (wire (pts (xy 135.89 245.745) (xy 135.89 247.015))
    (stroke (width 0) (type default) (color 0 0 0 0))
  )
  (wire (pts (xy 293.37 161.925) (xy 293.37 167.64))
    (stroke (width 0) (type default) (color 0 0 0 0))
  )
  (wire (pts (xy 185.928 60.96) (xy 185.928 66.04))
    (stroke (width 0) (type default) (color 0 0 0 0))
  )
  (wire (pts (xy 291.973 194.31) (xy 291.973 191.77))
    (stroke (width 0) (type default) (color 0 0 0 0))
  )
  (wire (pts (xy 314.96 191.77) (xy 316.23 191.77))
    (stroke (width 0) (type default) (color 0 0 0 0))
  )
  (wire (pts (xy 265.43 41.91) (xy 265.43 45.085))
    (stroke (width 0) (type default) (color 0 0 0 0))
  )
  (wire (pts (xy 126.365 115.062) (xy 126.365 116.713))
    (stroke (width 0) (type default) (color 0 0 0 0))
  )
  (wire (pts (xy 113.665 93.345) (xy 113.665 115.443))
    (stroke (width 0) (type default) (color 0 0 0 0))
  )
  (wire (pts (xy 106.045 179.07) (xy 111.125 179.07))
    (stroke (width 0) (type default) (color 0 0 0 0))
  )
  (wire (pts (xy 74.295 151.13) (xy 80.645 151.13))
    (stroke (width 0) (type default) (color 0 0 0 0))
  )
  (wire (pts (xy 66.675 179.451) (xy 66.675 177.8))
    (stroke (width 0) (type default) (color 0 0 0 0))
  )
  (wire (pts (xy 344.17 74.295) (xy 342.9 74.295))
    (stroke (width 0) (type default) (color 0 0 0 0))
  )
  (wire (pts (xy 36.195 54.61) (xy 57.785 54.61))
    (stroke (width 0) (type default) (color 0 0 0 0))
  )
  (polyline (pts (xy 203.2 279.4) (xy 203.2 25.4))
    (stroke (width 0) (type default) (color 0 0 0 0))
  )

  (wire (pts (xy 122.555 93.345) (xy 122.555 92.71))
    (stroke (width 0) (type default) (color 0 0 0 0))
  )
  (wire (pts (xy 145.542 142.24) (xy 153.543 142.24))
    (stroke (width 0) (type default) (color 0 0 0 0))
  )
  (wire (pts (xy 66.675 175.641) (xy 66.675 177.8))
    (stroke (width 0) (type default) (color 0 0 0 0))
  )
  (wire (pts (xy 74.295 54.61) (xy 78.74 54.61))
    (stroke (width 0) (type default) (color 0 0 0 0))
  )
  (wire (pts (xy 112.395 73.533) (xy 121.285 73.533))
    (stroke (width 0) (type default) (color 0 0 0 0))
  )
  (wire (pts (xy 107.95 154.94) (xy 107.95 158.75))
    (stroke (width 0) (type default) (color 0 0 0 0))
  )
  (wire (pts (xy 265.43 50.165) (xy 265.43 54.61))
    (stroke (width 0) (type default) (color 0 0 0 0))
  )
  (wire (pts (xy 126.365 74.93) (xy 126.365 78.74))
    (stroke (width 0) (type default) (color 0 0 0 0))
  )
  (wire (pts (xy 126.238 142.24) (xy 135.89 142.24))
    (stroke (width 0) (type default) (color 0 0 0 0))
  )
  (wire (pts (xy 113.665 58.42) (xy 113.665 54.61))
    (stroke (width 0) (type default) (color 0 0 0 0))
  )
  (wire (pts (xy 347.345 186.69) (xy 348.996 186.69))
    (stroke (width 0) (type default) (color 0 0 0 0))
  )
  (wire (pts (xy 126.238 142.24) (xy 126.238 147.574))
    (stroke (width 0) (type default) (color 0 0 0 0))
  )
  (wire (pts (xy 285.115 41.91) (xy 308.61 41.91))
    (stroke (width 0) (type default) (color 0 0 0 0))
  )
  (wire (pts (xy 314.96 186.69) (xy 325.628 186.69))
    (stroke (width 0) (type default) (color 0 0 0 0))
  )
  (wire (pts (xy 290.068 226.695) (xy 292.735 226.695))
    (stroke (width 0) (type default) (color 0 0 0 0))
  )
  (wire (pts (xy 361.315 221.615) (xy 365.76 221.615))
    (stroke (width 0) (type default) (color 0 0 0 0))
  )
  (wire (pts (xy 255.27 70.104) (xy 255.27 76.327))
    (stroke (width 0) (type default) (color 0 0 0 0))
  )
  (wire (pts (xy 56.642 95.25) (xy 56.642 96.52))
    (stroke (width 0) (type default) (color 0 0 0 0))
  )
  (wire (pts (xy 109.855 73.406) (xy 109.855 72.39))
    (stroke (width 0) (type default) (color 0 0 0 0))
  )
  (wire (pts (xy 126.238 152.654) (xy 126.238 158.75))
    (stroke (width 0) (type default) (color 0 0 0 0))
  )
  (wire (pts (xy 375.285 69.215) (xy 389.89 69.215))
    (stroke (width 0) (type default) (color 0 0 0 0))
  )
  (wire (pts (xy 365.76 186.69) (xy 369.57 186.69))
    (stroke (width 0) (type default) (color 0 0 0 0))
  )
  (wire (pts (xy 155.067 54.61) (xy 159.385 54.61))
    (stroke (width 0) (type default) (color 0 0 0 0))
  )
  (wire (pts (xy 125.095 95.123) (xy 133.985 95.123))
    (stroke (width 0) (type default) (color 0 0 0 0))
  )
  (wire (pts (xy 130.175 100.33) (xy 130.175 96.52))
    (stroke (width 0) (type default) (color 0 0 0 0))
  )
  (wire (pts (xy 289.052 191.77) (xy 290.322 191.77))
    (stroke (width 0) (type default) (color 0 0 0 0))
  )
  (wire (pts (xy 285.115 72.898) (xy 285.115 77.216))
    (stroke (width 0) (type default) (color 0 0 0 0))
  )
  (wire (pts (xy 290.322 191.77) (xy 291.973 191.77))
    (stroke (width 0) (type default) (color 0 0 0 0))
  )
  (wire (pts (xy 98.933 115.57) (xy 100.965 115.57))
    (stroke (width 0) (type default) (color 0 0 0 0))
  )
  (wire (pts (xy 74.295 54.61) (xy 74.295 142.24))
    (stroke (width 0) (type default) (color 0 0 0 0))
  )
  (wire (pts (xy 280.67 221.615) (xy 282.067 221.615))
    (stroke (width 0) (type default) (color 0 0 0 0))
  )
  (wire (pts (xy 291.465 156.845) (xy 292.862 156.845))
    (stroke (width 0) (type default) (color 0 0 0 0))
  )
  (wire (pts (xy 325.628 191.77) (xy 325.628 186.69))
    (stroke (width 0) (type default) (color 0 0 0 0))
  )
  (wire (pts (xy 31.242 54.61) (xy 36.195 54.61))
    (stroke (width 0) (type default) (color 0 0 0 0))
  )
  (wire (pts (xy 280.67 226.695) (xy 280.67 232.41))
    (stroke (width 0) (type default) (color 0 0 0 0))
  )
  (wire (pts (xy 126.365 74.93) (xy 153.543 74.93))
    (stroke (width 0) (type default) (color 0 0 0 0))
  )
  (wire (pts (xy 312.42 74.295) (xy 311.277 74.295))
    (stroke (width 0) (type default) (color 0 0 0 0))
  )
  (wire (pts (xy 106.045 163.83) (xy 123.19 163.83))
    (stroke (width 0) (type default) (color 0 0 0 0))
  )
  (wire (pts (xy 353.441 69.215) (xy 355.092 69.215))
    (stroke (width 0) (type default) (color 0 0 0 0))
  )
  (wire (pts (xy 321.31 156.845) (xy 325.882 156.845))
    (stroke (width 0) (type default) (color 0 0 0 0))
  )
  (wire (pts (xy 278.765 186.69) (xy 280.67 186.69))
    (stroke (width 0) (type default) (color 0 0 0 0))
  )
  (wire (pts (xy 108.585 58.42) (xy 108.585 52.451))
    (stroke (width 0) (type default) (color 0 0 0 0))
  )
  (wire (pts (xy 280.67 191.77) (xy 280.67 197.485))
    (stroke (width 0) (type default) (color 0 0 0 0))
  )
  (wire (pts (xy 115.57 154.94) (xy 115.57 161.29))
    (stroke (width 0) (type default) (color 0 0 0 0))
  )
  (wire (pts (xy 314.96 196.85) (xy 336.55 196.85))
    (stroke (width 0) (type default) (color 0 0 0 0))
  )
  (wire (pts (xy 290.322 191.135) (xy 290.322 191.77))
    (stroke (width 0) (type default) (color 0 0 0 0))
  )
  (wire (pts (xy 59.055 204.47) (xy 80.645 204.47))
    (stroke (width 0) (type default) (color 0 0 0 0))
  )
  (wire (pts (xy 285.623 151.765) (xy 294.64 151.765))
    (stroke (width 0) (type default) (color 0 0 0 0))
  )
  (wire (pts (xy 320.04 79.375) (xy 322.58 79.375))
    (stroke (width 0) (type default) (color 0 0 0 0))
  )
  (wire (pts (xy 336.55 186.69) (xy 347.345 186.69))
    (stroke (width 0) (type default) (color 0 0 0 0))
  )
  (wire (pts (xy 255.27 68.58) (xy 255.27 70.104))
    (stroke (width 0) (type default) (color 0 0 0 0))
  )
  (wire (pts (xy 173.355 54.61) (xy 173.355 58.42))
    (stroke (width 0) (type default) (color 0 0 0 0))
  )
  (wire (pts (xy 269.24 229.997) (xy 257.81 229.997))
    (stroke (width 0) (type default) (color 0 0 0 0))
  )
  (wire (pts (xy 135.89 142.24) (xy 145.542 142.24))
    (stroke (width 0) (type default) (color 0 0 0 0))
  )
  (wire (pts (xy 126.365 115.062) (xy 126.365 114.3))
    (stroke (width 0) (type default) (color 0 0 0 0))
  )
  (wire (pts (xy 285.115 41.91) (xy 285.115 50.8))
    (stroke (width 0) (type default) (color 0 0 0 0))
  )
  (wire (pts (xy 314.96 156.845) (xy 316.23 156.845))
    (stroke (width 0) (type default) (color 0 0 0 0))
  )
  (wire (pts (xy 290.068 226.695) (xy 290.068 225.933))
    (stroke (width 0) (type default) (color 0 0 0 0))
  )
  (wire (pts (xy 106.045 176.53) (xy 111.125 176.53))
    (stroke (width 0) (type default) (color 0 0 0 0))
  )
  (wire (pts (xy 285.623 156.845) (xy 285.623 151.765))
    (stroke (width 0) (type default) (color 0 0 0 0))
  )
  (wire (pts (xy 308.61 80.01) (xy 308.61 69.215))
    (stroke (width 0) (type default) (color 0 0 0 0))
  )
  (wire (pts (xy 59.055 195.58) (xy 59.055 96.52))
    (stroke (width 0) (type default) (color 0 0 0 0))
  )
  (wire (pts (xy 280.67 160.02) (xy 280.67 151.765))
    (stroke (width 0) (type default) (color 0 0 0 0))
  )
  (wire (pts (xy 336.55 196.85) (xy 336.55 193.04))
    (stroke (width 0) (type default) (color 0 0 0 0))
  )
  (wire (pts (xy 106.045 186.69) (xy 111.125 186.69))
    (stroke (width 0) (type default) (color 0 0 0 0))
  )
  (wire (pts (xy 291.973 191.77) (xy 294.64 191.77))
    (stroke (width 0) (type default) (color 0 0 0 0))
  )
  (wire (pts (xy 99.695 52.451) (xy 108.585 52.451))
    (stroke (width 0) (type default) (color 0 0 0 0))
  )
  (wire (pts (xy 321.31 226.695) (xy 325.628 226.695))
    (stroke (width 0) (type default) (color 0 0 0 0))
  )
  (wire (pts (xy 325.882 156.845) (xy 325.882 151.765))
    (stroke (width 0) (type default) (color 0 0 0 0))
  )
  (wire (pts (xy 389.89 69.215) (xy 389.89 70.485))
    (stroke (width 0) (type default) (color 0 0 0 0))
  )
  (wire (pts (xy 88.9 250.825) (xy 71.755 250.825))
    (stroke (width 0) (type default) (color 0 0 0 0))
  )
  (wire (pts (xy 56.642 96.52) (xy 59.055 96.52))
    (stroke (width 0) (type default) (color 0 0 0 0))
  )
  (wire (pts (xy 329.565 53.975) (xy 302.26 53.975))
    (stroke (width 0) (type default) (color 0 0 0 0))
  )
  (wire (pts (xy 348.869 221.615) (xy 361.315 221.615))
    (stroke (width 0) (type default) (color 0 0 0 0))
  )
  (wire (pts (xy 348.869 150.495) (xy 348.869 151.765))
    (stroke (width 0) (type default) (color 0 0 0 0))
  )
  (wire (pts (xy 59.055 213.36) (xy 59.055 211.201))
    (stroke (width 0) (type default) (color 0 0 0 0))
  )
  (wire (pts (xy 78.74 54.61) (xy 104.775 54.61))
    (stroke (width 0) (type default) (color 0 0 0 0))
  )
  (wire (pts (xy 361.95 151.765) (xy 366.395 151.765))
    (stroke (width 0) (type default) (color 0 0 0 0))
  )
  (wire (pts (xy 302.26 52.959) (xy 302.26 53.975))
    (stroke (width 0) (type default) (color 0 0 0 0))
  )
  (wire (pts (xy 100.965 118.11) (xy 100.965 132.08))
    (stroke (width 0) (type default) (color 0 0 0 0))
  )
  (wire (pts (xy 254 70.104) (xy 255.27 70.104))
    (stroke (width 0) (type default) (color 0 0 0 0))
  )
  (wire (pts (xy 106.045 184.15) (xy 111.125 184.15))
    (stroke (width 0) (type default) (color 0 0 0 0))
  )
  (wire (pts (xy 113.665 93.345) (xy 122.555 93.345))
    (stroke (width 0) (type default) (color 0 0 0 0))
  )
  (wire (pts (xy 265.43 72.39) (xy 265.43 84.455))
    (stroke (width 0) (type default) (color 0 0 0 0))
  )
  (wire (pts (xy 342.9 69.215) (xy 353.441 69.215))
    (stroke (width 0) (type default) (color 0 0 0 0))
  )
  (wire (pts (xy 226.695 87.63) (xy 228.6 87.63))
    (stroke (width 0) (type default) (color 0 0 0 0))
  )
  (wire (pts (xy 348.869 220.472) (xy 348.869 221.615))
    (stroke (width 0) (type default) (color 0 0 0 0))
  )
  (wire (pts (xy 113.665 92.71) (xy 113.665 93.345))
    (stroke (width 0) (type default) (color 0 0 0 0))
  )
  (wire (pts (xy 71.755 245.745) (xy 80.01 245.745))
    (stroke (width 0) (type default) (color 0 0 0 0))
  )
  (wire (pts (xy 126.238 158.75) (xy 160.655 158.75))
    (stroke (width 0) (type default) (color 0 0 0 0))
  )
  (wire (pts (xy 294.64 161.925) (xy 293.37 161.925))
    (stroke (width 0) (type default) (color 0 0 0 0))
  )
  (wire (pts (xy 66.675 177.8) (xy 80.645 177.8))
    (stroke (width 0) (type default) (color 0 0 0 0))
  )
  (wire (pts (xy 325.882 151.765) (xy 328.168 151.765))
    (stroke (width 0) (type default) (color 0 0 0 0))
  )
  (wire (pts (xy 128.27 250.825) (xy 109.855 250.825))
    (stroke (width 0) (type default) (color 0 0 0 0))
  )
  (wire (pts (xy 185.928 55.88) (xy 185.928 54.61))
    (stroke (width 0) (type default) (color 0 0 0 0))
  )
  (wire (pts (xy 274.32 54.61) (xy 277.495 54.61))
    (stroke (width 0) (type default) (color 0 0 0 0))
  )
  (wire (pts (xy 336.55 151.765) (xy 336.55 153.035))
    (stroke (width 0) (type default) (color 0 0 0 0))
  )
  (wire (pts (xy 87.63 245.745) (xy 90.17 245.745))
    (stroke (width 0) (type default) (color 0 0 0 0))
  )
  (wire (pts (xy 106.045 161.29) (xy 115.57 161.29))
    (stroke (width 0) (type default) (color 0 0 0 0))
  )
  (wire (pts (xy 332.74 221.615) (xy 336.55 221.615))
    (stroke (width 0) (type default) (color 0 0 0 0))
  )
  (wire (pts (xy 245.11 87.63) (xy 245.11 88.9))
    (stroke (width 0) (type default) (color 0 0 0 0))
  )
  (wire (pts (xy 325.628 221.615) (xy 327.66 221.615))
    (stroke (width 0) (type default) (color 0 0 0 0))
  )
  (wire (pts (xy 153.543 74.93) (xy 153.543 96.52))
    (stroke (width 0) (type default) (color 0 0 0 0))
  )
  (wire (pts (xy 158.75 246.38) (xy 160.655 246.38))
    (stroke (width 0) (type default) (color 0 0 0 0))
  )
  (wire (pts (xy 285.115 77.216) (xy 315.849 77.216))
    (stroke (width 0) (type default) (color 0 0 0 0))
  )
  (wire (pts (xy 145.542 163.83) (xy 160.655 163.83))
    (stroke (width 0) (type default) (color 0 0 0 0))
  )
  (wire (pts (xy 74.295 152.781) (xy 74.295 151.13))
    (stroke (width 0) (type default) (color 0 0 0 0))
  )
  (wire (pts (xy 318.135 74.295) (xy 322.58 74.295))
    (stroke (width 0) (type default) (color 0 0 0 0))
  )
  (wire (pts (xy 74.295 160.02) (xy 74.295 157.861))
    (stroke (width 0) (type default) (color 0 0 0 0))
  )
  (wire (pts (xy 225.425 41.91) (xy 255.27 41.91))
    (stroke (width 0) (type default) (color 0 0 0 0))
  )
  (wire (pts (xy 117.475 118.11) (xy 117.475 120.65))
    (stroke (width 0) (type default) (color 0 0 0 0))
  )
  (wire (pts (xy 294.64 231.775) (xy 293.37 231.775))
    (stroke (width 0) (type default) (color 0 0 0 0))
  )
  (wire (pts (xy 153.543 54.61) (xy 155.067 54.61))
    (stroke (width 0) (type default) (color 0 0 0 0))
  )
  (wire (pts (xy 308.61 69.215) (xy 308.61 41.91))
    (stroke (width 0) (type default) (color 0 0 0 0))
  )
  (wire (pts (xy 293.37 231.775) (xy 293.37 237.49))
    (stroke (width 0) (type default) (color 0 0 0 0))
  )
  (wire (pts (xy 106.045 173.99) (xy 111.125 173.99))
    (stroke (width 0) (type default) (color 0 0 0 0))
  )
  (wire (pts (xy 366.395 151.765) (xy 369.57 151.765))
    (stroke (width 0) (type default) (color 0 0 0 0))
  )
  (wire (pts (xy 59.055 195.58) (xy 80.645 195.58))
    (stroke (width 0) (type default) (color 0 0 0 0))
  )
  (wire (pts (xy 74.295 142.24) (xy 80.645 142.24))
    (stroke (width 0) (type default) (color 0 0 0 0))
  )
  (wire (pts (xy 325.628 186.69) (xy 326.39 186.69))
    (stroke (width 0) (type default) (color 0 0 0 0))
  )
  (wire (pts (xy 353.441 74.295) (xy 353.441 69.215))
    (stroke (width 0) (type default) (color 0 0 0 0))
  )
  (wire (pts (xy 349.25 74.295) (xy 353.441 74.295))
    (stroke (width 0) (type default) (color 0 0 0 0))
  )
  (wire (pts (xy 100.965 115.57) (xy 100.965 118.11))
    (stroke (width 0) (type default) (color 0 0 0 0))
  )
  (wire (pts (xy 348.869 151.765) (xy 361.95 151.765))
    (stroke (width 0) (type default) (color 0 0 0 0))
  )
  (wire (pts (xy 118.11 245.745) (xy 119.38 245.745))
    (stroke (width 0) (type default) (color 0 0 0 0))
  )
  (wire (pts (xy 66.675 188.341) (xy 66.675 186.69))
    (stroke (width 0) (type default) (color 0 0 0 0))
  )
  (wire (pts (xy 285.115 65.405) (xy 302.26 65.405))
    (stroke (width 0) (type default) (color 0 0 0 0))
  )
  (wire (pts (xy 282.194 186.69) (xy 294.64 186.69))
    (stroke (width 0) (type default) (color 0 0 0 0))
  )
  (wire (pts (xy 104.775 118.11) (xy 104.775 120.65))
    (stroke (width 0) (type default) (color 0 0 0 0))
  )
  (wire (pts (xy 153.543 96.52) (xy 153.543 142.24))
    (stroke (width 0) (type default) (color 0 0 0 0))
  )
  (wire (pts (xy 66.675 193.421) (xy 66.675 222.25))
    (stroke (width 0) (type default) (color 0 0 0 0))
  )
  (wire (pts (xy 364.49 76.581) (xy 364.49 79.375))
    (stroke (width 0) (type default) (color 0 0 0 0))
  )
  (wire (pts (xy 292.735 229.997) (xy 292.735 226.695))
    (stroke (width 0) (type default) (color 0 0 0 0))
  )
  (wire (pts (xy 342.9 79.375) (xy 364.49 79.375))
    (stroke (width 0) (type default) (color 0 0 0 0))
  )
  (wire (pts (xy 336.55 221.615) (xy 347.345 221.615))
    (stroke (width 0) (type default) (color 0 0 0 0))
  )
  (wire (pts (xy 347.345 221.615) (xy 347.345 222.885))
    (stroke (width 0) (type default) (color 0 0 0 0))
  )
  (wire (pts (xy 159.385 54.61) (xy 159.385 58.42))
    (stroke (width 0) (type default) (color 0 0 0 0))
  )
  (wire (pts (xy 361.315 221.615) (xy 361.315 222.885))
    (stroke (width 0) (type default) (color 0 0 0 0))
  )
  (wire (pts (xy 314.96 221.615) (xy 325.628 221.615))
    (stroke (width 0) (type default) (color 0 0 0 0))
  )
  (wire (pts (xy 371.094 68.072) (xy 371.094 69.215))
    (stroke (width 0) (type default) (color 0 0 0 0))
  )
  (wire (pts (xy 134.62 245.745) (xy 135.89 245.745))
    (stroke (width 0) (type default) (color 0 0 0 0))
  )
  (wire (pts (xy 276.225 194.31) (xy 291.973 194.31))
    (stroke (width 0) (type default) (color 0 0 0 0))
  )
  (wire (pts (xy 135.89 152.654) (xy 135.89 161.29))
    (stroke (width 0) (type default) (color 0 0 0 0))
  )
  (wire (pts (xy 278.765 151.765) (xy 280.67 151.765))
    (stroke (width 0) (type default) (color 0 0 0 0))
  )
  (wire (pts (xy 243.332 87.63) (xy 245.11 87.63))
    (stroke (width 0) (type default) (color 0 0 0 0))
  )
  (polyline (pts (xy 406.4 107.95) (xy 215.9 107.95))
    (stroke (width 0) (type default) (color 0 0 0 0))
  )

  (wire (pts (xy 59.055 215.011) (xy 59.055 213.36))
    (stroke (width 0) (type default) (color 0 0 0 0))
  )
  (wire (pts (xy 133.985 100.33) (xy 133.985 95.123))
    (stroke (width 0) (type default) (color 0 0 0 0))
  )
  (wire (pts (xy 107.95 158.75) (xy 126.238 158.75))
    (stroke (width 0) (type default) (color 0 0 0 0))
  )
  (wire (pts (xy 394.335 69.215) (xy 397.51 69.215))
    (stroke (width 0) (type default) (color 0 0 0 0))
  )
  (wire (pts (xy 255.27 50.165) (xy 255.27 68.58))
    (stroke (width 0) (type default) (color 0 0 0 0))
  )
  (wire (pts (xy 364.49 79.375) (xy 364.49 81.661))
    (stroke (width 0) (type default) (color 0 0 0 0))
  )
  (wire (pts (xy 347.345 186.69) (xy 347.345 187.96))
    (stroke (width 0) (type default) (color 0 0 0 0))
  )
  (wire (pts (xy 265.43 54.61) (xy 269.24 54.61))
    (stroke (width 0) (type default) (color 0 0 0 0))
  )
  (wire (pts (xy 135.255 115.062) (xy 135.255 114.3))
    (stroke (width 0) (type default) (color 0 0 0 0))
  )
  (wire (pts (xy 33.782 59.055) (xy 33.782 57.15))
    (stroke (width 0) (type default) (color 0 0 0 0))
  )
  (wire (pts (xy 139.065 100.33) (xy 139.065 96.52))
    (stroke (width 0) (type default) (color 0 0 0 0))
  )
  (wire (pts (xy 59.055 206.121) (xy 59.055 204.47))
    (stroke (width 0) (type default) (color 0 0 0 0))
  )
  (wire (pts (xy 292.862 160.782) (xy 292.862 156.845))
    (stroke (width 0) (type default) (color 0 0 0 0))
  )
  (wire (pts (xy 59.055 197.231) (xy 59.055 195.58))
    (stroke (width 0) (type default) (color 0 0 0 0))
  )
  (wire (pts (xy 126.365 116.713) (xy 126.365 118.11))
    (stroke (width 0) (type default) (color 0 0 0 0))
  )
  (wire (pts (xy 394.335 41.91) (xy 397.51 41.91))
    (stroke (width 0) (type default) (color 0 0 0 0))
  )
  (wire (pts (xy 365.76 221.615) (xy 369.57 221.615))
    (stroke (width 0) (type default) (color 0 0 0 0))
  )
  (wire (pts (xy 74.295 148.971) (xy 74.295 151.13))
    (stroke (width 0) (type default) (color 0 0 0 0))
  )
  (wire (pts (xy 126.365 118.11) (xy 126.365 132.08))
    (stroke (width 0) (type default) (color 0 0 0 0))
  )
  (wire (pts (xy 78.74 55.88) (xy 78.74 54.61))
    (stroke (width 0) (type default) (color 0 0 0 0))
  )
  (wire (pts (xy 285.115 65.405) (xy 285.115 67.818))
    (stroke (width 0) (type default) (color 0 0 0 0))
  )
  (wire (pts (xy 285.115 83.693) (xy 285.115 86.995))
    (stroke (width 0) (type default) (color 0 0 0 0))
  )
  (wire (pts (xy 238.252 87.63) (xy 236.22 87.63))
    (stroke (width 0) (type default) (color 0 0 0 0))
  )
  (wire (pts (xy 57.785 54.61) (xy 69.215 54.61))
    (stroke (width 0) (type default) (color 0 0 0 0))
  )
  (wire (pts (xy 117.475 118.11) (xy 113.665 118.11))
    (stroke (width 0) (type default) (color 0 0 0 0))
  )
  (wire (pts (xy 364.49 69.215) (xy 371.094 69.215))
    (stroke (width 0) (type default) (color 0 0 0 0))
  )
  (wire (pts (xy 360.172 69.215) (xy 364.49 69.215))
    (stroke (width 0) (type default) (color 0 0 0 0))
  )
  (wire (pts (xy 333.248 151.765) (xy 336.55 151.765))
    (stroke (width 0) (type default) (color 0 0 0 0))
  )
  (wire (pts (xy 285.115 63.5) (xy 285.115 65.405))
    (stroke (width 0) (type default) (color 0 0 0 0))
  )
  (wire (pts (xy 282.067 220.853) (xy 282.067 221.615))
    (stroke (width 0) (type default) (color 0 0 0 0))
  )
  (wire (pts (xy 347.345 151.765) (xy 348.869 151.765))
    (stroke (width 0) (type default) (color 0 0 0 0))
  )
  (wire (pts (xy 263.906 55.88) (xy 265.43 55.88))
    (stroke (width 0) (type default) (color 0 0 0 0))
  )
  (wire (pts (xy 255.27 41.91) (xy 265.43 41.91))
    (stroke (width 0) (type default) (color 0 0 0 0))
  )
  (wire (pts (xy 336.55 151.765) (xy 347.345 151.765))
    (stroke (width 0) (type default) (color 0 0 0 0))
  )
  (wire (pts (xy 74.295 143.891) (xy 74.295 142.24))
    (stroke (width 0) (type default) (color 0 0 0 0))
  )
  (wire (pts (xy 364.49 69.215) (xy 364.49 71.501))
    (stroke (width 0) (type default) (color 0 0 0 0))
  )
  (polyline (pts (xy 406.4 25.4) (xy 215.9 25.4))
    (stroke (width 0) (type default) (color 0 0 0 0))
  )

  (wire (pts (xy 106.045 196.85) (xy 109.22 196.85))
    (stroke (width 0) (type default) (color 0 0 0 0))
  )
  (wire (pts (xy 336.55 203.2) (xy 336.55 205.74))
    (stroke (width 0) (type default) (color 0 0 0 0))
  )
  (wire (pts (xy 115.57 161.29) (xy 135.89 161.29))
    (stroke (width 0) (type default) (color 0 0 0 0))
  )
  (wire (pts (xy 331.47 186.69) (xy 336.55 186.69))
    (stroke (width 0) (type default) (color 0 0 0 0))
  )
  (wire (pts (xy 302.26 53.975) (xy 302.26 65.405))
    (stroke (width 0) (type default) (color 0 0 0 0))
  )
  (wire (pts (xy 125.095 116.713) (xy 126.365 116.713))
    (stroke (width 0) (type default) (color 0 0 0 0))
  )
  (wire (pts (xy 315.849 77.216) (xy 318.135 77.216))
    (stroke (width 0) (type default) (color 0 0 0 0))
  )
  (wire (pts (xy 361.315 187.96) (xy 361.315 186.69))
    (stroke (width 0) (type default) (color 0 0 0 0))
  )
  (wire (pts (xy 308.61 41.91) (xy 327.025 41.91))
    (stroke (width 0) (type default) (color 0 0 0 0))
  )
  (wire (pts (xy 117.475 74.93) (xy 117.475 78.74))
    (stroke (width 0) (type default) (color 0 0 0 0))
  )
  (wire (pts (xy 112.395 78.74) (xy 112.395 73.533))
    (stroke (width 0) (type default) (color 0 0 0 0))
  )
  (wire (pts (xy 265.43 55.88) (xy 265.43 64.77))
    (stroke (width 0) (type default) (color 0 0 0 0))
  )
  (wire (pts (xy 265.43 41.91) (xy 285.115 41.91))
    (stroke (width 0) (type default) (color 0 0 0 0))
  )
  (wire (pts (xy 261.62 68.58) (xy 255.27 68.58))
    (stroke (width 0) (type default) (color 0 0 0 0))
  )
  (wire (pts (xy 361.95 153.035) (xy 361.95 151.765))
    (stroke (width 0) (type default) (color 0 0 0 0))
  )
  (wire (pts (xy 66.675 74.93) (xy 117.475 74.93))
    (stroke (width 0) (type default) (color 0 0 0 0))
  )
  (wire (pts (xy 280.67 186.69) (xy 280.67 191.77))
    (stroke (width 0) (type default) (color 0 0 0 0))
  )
  (wire (pts (xy 336.55 221.615) (xy 336.55 223.52))
    (stroke (width 0) (type default) (color 0 0 0 0))
  )
  (wire (pts (xy 317.5 74.295) (xy 318.135 74.295))
    (stroke (width 0) (type default) (color 0 0 0 0))
  )
  (wire (pts (xy 177.165 246.38) (xy 177.165 247.65))
    (stroke (width 0) (type default) (color 0 0 0 0))
  )
  (wire (pts (xy 292.735 226.695) (xy 294.64 226.695))
    (stroke (width 0) (type default) (color 0 0 0 0))
  )
  (wire (pts (xy 289.56 160.782) (xy 292.862 160.782))
    (stroke (width 0) (type default) (color 0 0 0 0))
  )
  (wire (pts (xy 130.175 118.11) (xy 126.365 118.11))
    (stroke (width 0) (type default) (color 0 0 0 0))
  )
  (wire (pts (xy 347.345 221.615) (xy 348.869 221.615))
    (stroke (width 0) (type default) (color 0 0 0 0))
  )
  (wire (pts (xy 347.345 151.765) (xy 347.345 153.035))
    (stroke (width 0) (type default) (color 0 0 0 0))
  )
  (wire (pts (xy 96.52 245.745) (xy 96.52 247.015))
    (stroke (width 0) (type default) (color 0 0 0 0))
  )
  (wire (pts (xy 185.928 54.61) (xy 192.278 54.61))
    (stroke (width 0) (type default) (color 0 0 0 0))
  )
  (wire (pts (xy 294.64 196.85) (xy 293.37 196.85))
    (stroke (width 0) (type default) (color 0 0 0 0))
  )
  (wire (pts (xy 336.55 231.775) (xy 336.55 235.585))
    (stroke (width 0) (type default) (color 0 0 0 0))
  )
  (wire (pts (xy 127 245.745) (xy 129.54 245.745))
    (stroke (width 0) (type default) (color 0 0 0 0))
  )
  (wire (pts (xy 113.665 115.443) (xy 113.665 118.11))
    (stroke (width 0) (type default) (color 0 0 0 0))
  )
  (wire (pts (xy 66.675 168.91) (xy 66.675 74.93))
    (stroke (width 0) (type default) (color 0 0 0 0))
  )
  (wire (pts (xy 74.295 222.25) (xy 66.675 222.25))
    (stroke (width 0) (type default) (color 0 0 0 0))
  )
  (wire (pts (xy 311.277 74.295) (xy 311.277 69.215))
    (stroke (width 0) (type default) (color 0 0 0 0))
  )
  (wire (pts (xy 57.785 53.467) (xy 57.785 54.61))
    (stroke (width 0) (type default) (color 0 0 0 0))
  )

  (text "Source selector" (at 14.605 30.48 0)
    (effects (font (size 2.0066 2.0066) (thickness 0.4013) bold) (justify left bottom))
  )
  (text "Indicator leds" (at 113.665 236.22 0)
    (effects (font (size 2.54 2.54)) (justify left bottom))
  )
  (text "Bypass transistor" (at 323.85 33.02 0)
    (effects (font (size 1.27 1.27)) (justify left bottom))
  )
  (text "5V DCDC & bypass" (at 217.17 30.48 0)
    (effects (font (size 2.0066 2.0066) (thickness 0.4013) bold) (justify left bottom))
  )
  (text "Auxiliary Power Connector" (at 17.78 46.355 0)
    (effects (font (size 1.27 1.27)) (justify left bottom))
  )
  (text "5V0, lowest priority" (at 35.56 99.06 0)
    (effects (font (size 1.27 1.27)) (justify left bottom))
  )
  (text "Vswitch = Vref(1+R91/R92)\n5.5V = 1.24V(1+R91/R92)\nR91/R92 = 3.4354\n1.24V(1+7k5/2k2) = 5.4672V"
    (at 220.98 64.135 0)
    (effects (font (size 1.27 1.27)) (justify left bottom))
  )
  (text "1V2" (at 246.38 226.695 0)
    (effects (font (size 2.0066 2.0066) (thickness 0.4013) bold) (justify left bottom))
  )
  (text "3V8" (at 245.11 156.845 0)
    (effects (font (size 2.0066 2.0066) (thickness 0.4013) bold) (justify left bottom))
  )
  (text "If VDD > 5.5V use converter\nelse bypass converter and pass \n5V directly to power line"
    (at 266.7 35.56 0)
    (effects (font (size 1.27 1.27)) (justify left bottom))
  )
  (text "Power section" (at 14.605 19.685 0)
    (effects (font (size 2.9972 2.9972) (thickness 0.5994) bold) (justify left bottom))
  )
  (text "3V3" (at 245.745 191.77 0)
    (effects (font (size 2.0066 2.0066) (thickness 0.4013) bold) (justify left bottom))
  )
  (text "Fall:\nUV 4.8V\nOV 18.4V\n\nRise:\nUV 4.85V\nOV 18.45V" (at 43.18 160.02 0)
    (effects (font (size 1.27 1.27)) (justify left bottom))
  )
  (text "Vswitch = 5.47V ->" (at 231.14 69.215 0)
    (effects (font (size 1.27 1.27)) (justify left bottom))
  )
  (text "Fall:\nUV 4.8V\nOV 18.4V\n\nRise:\nUV 4.85V\nOV 18.45V" (at 43.18 213.36 0)
    (effects (font (size 1.27 1.27)) (justify left bottom))
  )
  (text "main power line \n5V - 20V" (at 228.6 46.99 0)
    (effects (font (size 1.27 1.27)) (justify left bottom))
  )
  (text "5-15V, middle priority" (at 35.56 77.47 0)
    (effects (font (size 1.27 1.27)) (justify left bottom))
  )
  (text "Fall:\nUV 4.8V\nOV 18.4V\n\nRise:\nUV 4.85V\nOV 18.45V" (at 43.18 186.69 0)
    (effects (font (size 1.27 1.27)) (justify left bottom))
  )
  (text "System DCDCs" (at 218.44 125.73 0)
    (effects (font (size 2.0066 2.0066) (thickness 0.4013) bold) (justify left bottom))
  )
  (text "5-18V, highest priority" (at 35.56 57.15 0)
    (effects (font (size 1.27 1.27)) (justify left bottom))
  )
  (text "~100mV \nhysteresis" (at 109.855 197.485 0)
    (effects (font (size 1.27 1.27)) (justify left bottom))
  )

  (label "USB_PD_VALID" (at 160.655 161.29 180)
    (effects (font (size 1.27 1.27)) (justify right bottom))
  )
  (label "5V_DC_DC_ENABLE" (at 287.655 77.216 0)
    (effects (font (size 1.27 1.27)) (justify left bottom))
  )
  (label "G1" (at 100.965 132.08 90)
    (effects (font (size 1.27 1.27)) (justify left bottom))
  )
  (label "G2" (at 113.665 132.08 90)
    (effects (font (size 1.27 1.27)) (justify left bottom))
  )
  (label "VS2" (at 111.125 179.07 180)
    (effects (font (size 1.27 1.27)) (justify right bottom))
  )
  (label "AUX_VALID" (at 160.655 163.83 180)
    (effects (font (size 1.27 1.27)) (justify right bottom))
  )
  (label "G3" (at 111.125 186.69 180)
    (effects (font (size 1.27 1.27)) (justify right bottom))
  )
  (label "VS1" (at 111.125 173.99 180)
    (effects (font (size 1.27 1.27)) (justify right bottom))
  )
  (label "VS1" (at 105.029 52.451 0)
    (effects (font (size 1.27 1.27)) (justify left bottom))
  )
  (label "AUX_VDD" (at 71.755 245.745 0)
    (effects (font (size 1.27 1.27)) (justify left bottom))
  )
  (label "G2" (at 111.125 181.61 180)
    (effects (font (size 1.27 1.27)) (justify right bottom))
  )
  (label "G1" (at 111.125 176.53 180)
    (effects (font (size 1.27 1.27)) (justify right bottom))
  )
  (label "POE_VALID" (at 160.655 158.75 180)
    (effects (font (size 1.27 1.27)) (justify right bottom))
  )
  (label "VS2" (at 117.602 73.533 0)
    (effects (font (size 1.27 1.27)) (justify left bottom))
  )
  (label "VS3" (at 111.125 184.15 180)
    (effects (font (size 1.27 1.27)) (justify right bottom))
  )
  (label "AUX_VALID" (at 71.755 250.825 0)
    (effects (font (size 1.27 1.27)) (justify left bottom))
  )
  (label "AUX_VDD" (at 40.005 54.61 0)
    (effects (font (size 1.27 1.27)) (justify left bottom))
  )
  (label "USB_PD_VALID" (at 109.855 250.825 0)
    (effects (font (size 1.27 1.27)) (justify left bottom))
  )
  (label "G3" (at 126.365 132.08 90)
    (effects (font (size 1.27 1.27)) (justify left bottom))
  )
  (label "POE_VALID" (at 150.495 251.46 0)
    (effects (font (size 1.27 1.27)) (justify left bottom))
  )
  (label "BYPASS_EN" (at 222.25 92.71 0)
    (effects (font (size 1.27 1.27)) (justify left bottom))
  )
  (label "BYPASS_EN" (at 318.135 53.975 0)
    (effects (font (size 1.27 1.27)) (justify left bottom))
  )
  (label "VS3" (at 130.429 95.123 0)
    (effects (font (size 1.27 1.27)) (justify left bottom))
  )

  (global_label "5V_POE" (shape input) (at 28.575 96.52 180) (fields_autoplaced)
    (effects (font (size 1.27 1.27)) (justify right))
    (property "Intersheet References" "${INTERSHEET_REFS}" (id 0) (at 0 0 0)
      (effects (font (size 1.27 1.27)) hide)
    )
  )
  (global_label "PD_VDD" (shape input) (at 118.11 245.745 180) (fields_autoplaced)
    (effects (font (size 1.27 1.27)) (justify right))
    (property "Intersheet References" "${INTERSHEET_REFS}" (id 0) (at 0 0 0)
      (effects (font (size 1.27 1.27)) hide)
    )
  )
  (global_label "VDD" (shape input) (at 278.765 151.765 180) (fields_autoplaced)
    (effects (font (size 1.27 1.27)) (justify right))
    (property "Intersheet References" "${INTERSHEET_REFS}" (id 0) (at 0 0 0)
      (effects (font (size 1.27 1.27)) hide)
    )
  )
  (global_label "VDD" (shape output) (at 192.278 54.61 0) (fields_autoplaced)
    (effects (font (size 1.27 1.27)) (justify left))
    (property "Intersheet References" "${INTERSHEET_REFS}" (id 0) (at -5.207 0 0)
      (effects (font (size 1.27 1.27)) hide)
    )
  )
  (global_label "1V2_SYS" (shape input) (at 369.57 221.615 0) (fields_autoplaced)
    (effects (font (size 1.27 1.27)) (justify left))
    (property "Intersheet References" "${INTERSHEET_REFS}" (id 0) (at 0 0 0)
      (effects (font (size 1.27 1.27)) hide)
    )
  )
  (global_label "5V_SYS" (shape output) (at 397.51 69.215 0) (fields_autoplaced)
    (effects (font (size 1.27 1.27)) (justify left))
    (property "Intersheet References" "${INTERSHEET_REFS}" (id 0) (at 0 0 0)
      (effects (font (size 1.27 1.27)) hide)
    )
  )
  (global_label "5V_POE" (shape input) (at 158.75 246.38 180) (fields_autoplaced)
    (effects (font (size 1.27 1.27)) (justify right))
    (property "Intersheet References" "${INTERSHEET_REFS}" (id 0) (at 0 0 0)
      (effects (font (size 1.27 1.27)) hide)
    )
  )
  (global_label "3V3_SYS" (shape output) (at 369.57 186.69 0) (fields_autoplaced)
    (effects (font (size 1.27 1.27)) (justify left))
    (property "Intersheet References" "${INTERSHEET_REFS}" (id 0) (at 0 0 0)
      (effects (font (size 1.27 1.27)) hide)
    )
  )
  (global_label "VDD" (shape input) (at 225.425 41.91 180) (fields_autoplaced)
    (effects (font (size 1.27 1.27)) (justify right))
    (property "Intersheet References" "${INTERSHEET_REFS}" (id 0) (at 0 0 0)
      (effects (font (size 1.27 1.27)) hide)
    )
  )
  (global_label "5V_SYS" (shape output) (at 397.51 41.91 0) (fields_autoplaced)
    (effects (font (size 1.27 1.27)) (justify left))
    (property "Intersheet References" "${INTERSHEET_REFS}" (id 0) (at 0 0 0)
      (effects (font (size 1.27 1.27)) hide)
    )
  )
  (global_label "5V_SYS" (shape input) (at 278.765 221.615 180) (fields_autoplaced)
    (effects (font (size 1.27 1.27)) (justify right))
    (property "Intersheet References" "${INTERSHEET_REFS}" (id 0) (at 0 0 0)
      (effects (font (size 1.27 1.27)) hide)
    )
  )
  (global_label "3V8_SYS" (shape output) (at 369.57 151.765 0) (fields_autoplaced)
    (effects (font (size 1.27 1.27)) (justify left))
    (property "Intersheet References" "${INTERSHEET_REFS}" (id 0) (at 0 0 0)
      (effects (font (size 1.27 1.27)) hide)
    )
  )
  (global_label "3V3_SYS_EN" (shape input) (at 259.715 194.31 180) (fields_autoplaced)
    (effects (font (size 1.27 1.27)) (justify right))
    (property "Intersheet References" "${INTERSHEET_REFS}" (id 0) (at 0 0 0)
      (effects (font (size 1.27 1.27)) hide)
    )
  )
  (global_label "PD_VDD" (shape input) (at 28.575 74.93 180) (fields_autoplaced)
    (effects (font (size 1.27 1.27)) (justify right))
    (property "Intersheet References" "${INTERSHEET_REFS}" (id 0) (at 0 0 0)
      (effects (font (size 1.27 1.27)) hide)
    )
  )
  (global_label "VDD" (shape input) (at 278.765 186.69 180) (fields_autoplaced)
    (effects (font (size 1.27 1.27)) (justify right))
    (property "Intersheet References" "${INTERSHEET_REFS}" (id 0) (at 0 0 0)
      (effects (font (size 1.27 1.27)) hide)
    )
  )
  (global_label "VDD" (shape input) (at 226.695 87.63 180) (fields_autoplaced)
    (effects (font (size 1.27 1.27)) (justify right))
    (property "Intersheet References" "${INTERSHEET_REFS}" (id 0) (at 0 0 0)
      (effects (font (size 1.27 1.27)) hide)
    )
  )
  (global_label "1V2_SYS_EN" (shape input) (at 257.81 229.997 180) (fields_autoplaced)
    (effects (font (size 1.27 1.27)) (justify right))
    (property "Intersheet References" "${INTERSHEET_REFS}" (id 0) (at -1.905 0.762 0)
      (effects (font (size 1.27 1.27)) hide)
    )
  )

  (symbol (lib_id "sa800u-baseboard-hw:LMV431_SOT-23-5") (at 261.62 68.58 0) (unit 1)
    (in_bom yes) (on_board yes) (fields_autoplaced)
    (property "Reference" "U18" (id 0) (at 269.24 66.2875 0)
      (effects (font (size 1.27 1.27)) (justify left))
    )
    (property "Value" "LMV431_SOT-23-5" (id 1) (at 273.05 77.47 0)
      (effects (font (size 1.27 1.27) (thickness 0.15)) (justify left bottom) hide)
    )
    (property "Footprint" "sa800u-baseboard-hw-footprints:SOT-23-5" (id 2) (at 273.05 80.01 0)
      (effects (font (size 1.27 1.27) (thickness 0.15)) (justify left bottom) hide)
    )
    (property "Datasheet" "https://www.ti.com/lit/ds/symlink/lmv431a.pdf?HQS=dis-dk-null-digikeymode-dsf-pf-null-wwe&ts=1640859539059&ref_url=https%253A%252F%252Fwww.ti.com%252Fgeneral%252Fdocs%252Fsuppproductinfo.tsp%253FdistId%253D10%2526gotoUrl%253Dhttps%253A%252F%252Fwww.ti.com%252Flit%252Fgpn%252Flmv431a" (id 3) (at 273.05 82.55 0)
      (effects (font (size 1.27 1.27) (thickness 0.15)) (justify left bottom) hide)
    )
    (property "MPN" "LMV431IM5" (id 4) (at 269.24 68.8275 0)
      (effects (font (size 1.27 1.27) (thickness 0.15)) (justify left))
    )
    (property "Manufacturer" "Texas Instruments" (id 5) (at 273.05 85.09 0)
      (effects (font (size 1.27 1.27) (thickness 0.15)) (justify left bottom) hide)
    )
    (property "Author" "Antmicro" (id 6) (at 273.05 87.63 0)
      (effects (font (size 1.27 1.27) (thickness 0.15)) (justify left bottom) hide)
    )
    (property "License" "Apache-2.0" (id 7) (at 273.05 90.17 0)
      (effects (font (size 1.27 1.27) (thickness 0.15)) (justify left bottom) hide)
    )
    (pin "1")
    (pin "2")
    (pin "3")
    (pin "4")
    (pin "5")
  )

  (symbol (lib_id "sa800u-baseboard-hw:C_10u_25V_0603") (at 308.61 80.01 270) (unit 1)
    (in_bom yes) (on_board yes) (fields_autoplaced)
    (property "Reference" "C131" (id 0) (at 306.07 81.2863 90)
      (effects (font (size 1.524 1.524)) (justify right))
    )
    (property "Value" "C_10u_25V_0603" (id 1) (at 304.8 80.01 0)
      (effects (font (size 1.524 1.524)) hide)
    )
    (property "Footprint" "sa800u-baseboard-hw-footprints:C_0603_1608Metric" (id 2) (at 313.69 85.09 0)
      (effects (font (size 1.524 1.524)) (justify left) hide)
    )
    (property "Datasheet" " " (id 3) (at 308.61 80.01 0)
      (effects (font (size 1.27 1.27)) hide)
    )
    (property "Manufacturer" "TDK" (id 4) (at 318.77 85.09 0)
      (effects (font (size 1.524 1.524)) (justify left) hide)
    )
    (property "MPN" "C1608X5R1E106M080AC" (id 5) (at 316.23 85.09 0)
      (effects (font (size 1.524 1.524)) (justify left) hide)
    )
    (property "Val" "10u/25V" (id 6) (at 306.07 84.4612 90)
      (effects (font (size 1.27 1.27)) (justify right))
    )
    (property "License" "Apache-2.0" (id 7) (at 285.75 100.33 0)
      (effects (font (size 1.27 1.27) (thickness 0.15)) (justify left bottom) hide)
    )
    (property "Author" "Antmicro" (id 8) (at 283.21 100.33 0)
      (effects (font (size 1.27 1.27) (thickness 0.15)) (justify left bottom) hide)
    )
    (property "Voltage" "" (id 9) (at 280.67 100.33 0)
      (effects (font (size 1.27 1.27)) (justify left bottom) hide)
    )
    (property "Dielectric" "" (id 10) (at 278.13 100.33 0)
      (effects (font (size 1.27 1.27)) (justify left bottom) hide)
    )
    (pin "1")
    (pin "2")
  )

  (symbol (lib_id "sa800u-baseboard-hw:R_2k2_0402") (at 265.43 45.085 270) (unit 1)
    (in_bom yes) (on_board yes) (fields_autoplaced)
    (property "Reference" "R125" (id 0) (at 267.97 46.355 90)
      (effects (font (size 1.524 1.524)) (justify left))
    )
    (property "Value" "R_2k2_0402" (id 1) (at 261.62 45.085 0)
      (effects (font (size 1.524 1.524)) hide)
    )
    (property "Footprint" "sa800u-baseboard-hw-footprints:R_0402_1005Metric" (id 2) (at 270.51 50.165 0)
      (effects (font (size 1.524 1.524)) (justify left) hide)
    )
    (property "Datasheet" "https://www.bourns.com/docs/product-datasheets/cr.pdf" (id 3) (at 265.43 45.085 0)
      (effects (font (size 1.27 1.27)) hide)
    )
    (property "Manufacturer" "Bourns" (id 4) (at 275.59 50.165 0)
      (effects (font (size 1.524 1.524)) (justify left) hide)
    )
    (property "MPN" "CR0402-FX-2201GLF" (id 5) (at 273.05 50.165 0)
      (effects (font (size 1.524 1.524)) (justify left) hide)
    )
    (property "Val" "2k2" (id 6) (at 267.97 49.5299 90)
      (effects (font (size 1.27 1.27)) (justify left))
    )
    (property "License" "Apache-2.0" (id 7) (at 240.03 65.405 0)
      (effects (font (size 1.27 1.27) (thickness 0.15)) (justify left bottom) hide)
    )
    (property "Author" "Antmicro" (id 8) (at 237.49 65.405 0)
      (effects (font (size 1.27 1.27) (thickness 0.15)) (justify left bottom) hide)
    )
    (property "Tolerance" "1%" (id 9) (at 255.27 65.405 0)
      (effects (font (size 1.27 1.27)) (justify left bottom) hide)
    )
    (pin "1")
    (pin "2")
  )

  (symbol (lib_id "sa800u-baseboard-hw:R_7k5_0402") (at 255.27 45.085 270) (unit 1)
    (in_bom yes) (on_board yes) (fields_autoplaced)
    (property "Reference" "R123" (id 0) (at 252.73 46.355 90)
      (effects (font (size 1.524 1.524)) (justify right))
    )
    (property "Value" "R_7k5_0402" (id 1) (at 251.46 45.085 0)
      (effects (font (size 1.524 1.524)) hide)
    )
    (property "Footprint" "sa800u-baseboard-hw-footprints:R_0402_1005Metric" (id 2) (at 260.35 50.165 0)
      (effects (font (size 1.524 1.524)) (justify left) hide)
    )
    (property "Datasheet" "https://www.bourns.com/docs/product-datasheets/cr.pdf" (id 3) (at 255.27 45.085 0)
      (effects (font (size 1.27 1.27)) hide)
    )
    (property "Manufacturer" "Bourns" (id 4) (at 265.43 50.165 0)
      (effects (font (size 1.524 1.524)) (justify left) hide)
    )
    (property "MPN" "CR0402-FX-7501GLF" (id 5) (at 262.89 50.165 0)
      (effects (font (size 1.524 1.524)) (justify left) hide)
    )
    (property "Val" "7k5" (id 6) (at 252.73 49.5299 90)
      (effects (font (size 1.27 1.27)) (justify right))
    )
    (property "License" "Apache-2.0" (id 7) (at 229.87 65.405 0)
      (effects (font (size 1.27 1.27) (thickness 0.15)) (justify left bottom) hide)
    )
    (property "Author" "Antmicro" (id 8) (at 227.33 65.405 0)
      (effects (font (size 1.27 1.27) (thickness 0.15)) (justify left bottom) hide)
    )
    (property "Tolerance" "1%" (id 9) (at 245.11 65.405 0)
      (effects (font (size 1.27 1.27)) (justify left bottom) hide)
    )
    (pin "1")
    (pin "2")
  )

  (symbol (lib_id "sa800u-baseboard-hw:R_2k2_0402") (at 255.27 76.327 270) (unit 1)
    (in_bom yes) (on_board yes) (fields_autoplaced)
    (property "Reference" "R124" (id 0) (at 257.81 77.597 90)
      (effects (font (size 1.524 1.524)) (justify left))
    )
    (property "Value" "R_2k2_0402" (id 1) (at 251.46 76.327 0)
      (effects (font (size 1.524 1.524)) hide)
    )
    (property "Footprint" "sa800u-baseboard-hw-footprints:R_0402_1005Metric" (id 2) (at 260.35 81.407 0)
      (effects (font (size 1.524 1.524)) (justify left) hide)
    )
    (property "Datasheet" "https://www.bourns.com/docs/product-datasheets/cr.pdf" (id 3) (at 255.27 76.327 0)
      (effects (font (size 1.27 1.27)) hide)
    )
    (property "Manufacturer" "Bourns" (id 4) (at 265.43 81.407 0)
      (effects (font (size 1.524 1.524)) (justify left) hide)
    )
    (property "MPN" "CR0402-FX-2201GLF" (id 5) (at 262.89 81.407 0)
      (effects (font (size 1.524 1.524)) (justify left) hide)
    )
    (property "Val" "2k2" (id 6) (at 257.81 80.7719 90)
      (effects (font (size 1.27 1.27)) (justify left))
    )
    (property "License" "Apache-2.0" (id 7) (at 229.87 96.647 0)
      (effects (font (size 1.27 1.27) (thickness 0.15)) (justify left bottom) hide)
    )
    (property "Author" "Antmicro" (id 8) (at 227.33 96.647 0)
      (effects (font (size 1.27 1.27) (thickness 0.15)) (justify left bottom) hide)
    )
    (property "Tolerance" "1%" (id 9) (at 245.11 96.647 0)
      (effects (font (size 1.27 1.27)) (justify left bottom) hide)
    )
    (pin "1")
    (pin "2")
  )

  (symbol (lib_id "sa800u-baseboard-hw:C_100n_0402") (at 344.17 74.295 0) (unit 1)
    (in_bom yes) (on_board yes)
    (property "Reference" "C138" (id 0) (at 350.393 72.898 0)
      (effects (font (size 1.524 1.524)))
    )
    (property "Value" "C_100n_0402" (id 1) (at 344.17 78.105 0)
      (effects (font (size 1.524 1.524)) hide)
    )
    (property "Footprint" "sa800u-baseboard-hw-footprints:C_0402_1005Metric" (id 2) (at 349.25 69.215 0)
      (effects (font (size 1.524 1.524)) (justify left) hide)
    )
    (property "Datasheet" "https://search.murata.co.jp/Ceramy/image/img/A01X/G101/ENG/GRM155R61H104KE14-01.pdf" (id 3) (at 344.17 74.295 0)
      (effects (font (size 1.27 1.27)) hide)
    )
    (property "Manufacturer" "Murata" (id 4) (at 349.25 64.135 0)
      (effects (font (size 1.524 1.524)) (justify left) hide)
    )
    (property "MPN" "GRM155R61H104KE14D" (id 5) (at 349.25 66.675 0)
      (effects (font (size 1.524 1.524)) (justify left) hide)
    )
    (property "Val" "100n" (id 6) (at 350.393 75.438 0))
    (property "License" "Apache-2.0" (id 7) (at 364.49 97.155 0)
      (effects (font (size 1.27 1.27) (thickness 0.15)) (justify left bottom) hide)
    )
    (property "Author" "Antmicro" (id 8) (at 364.49 99.695 0)
      (effects (font (size 1.27 1.27) (thickness 0.15)) (justify left bottom) hide)
    )
    (property "Voltage" "50V" (id 9) (at 364.49 102.235 0)
      (effects (font (size 1.27 1.27)) (justify left bottom) hide)
    )
    (property "Dielectric" "X5R" (id 10) (at 364.49 104.775 0)
      (effects (font (size 1.27 1.27)) (justify left bottom) hide)
    )
    (pin "1")
    (pin "2")
  )

  (symbol (lib_id "sa800u-baseboard-hw:PWR_FLAG") (at 366.395 151.765 0) (unit 1)
    (in_bom yes) (on_board yes) (fields_autoplaced)
    (property "Reference" "#FLG024" (id 0) (at 366.395 149.86 0)
      (effects (font (size 1.27 1.27)) hide)
    )
    (property "Value" "PWR_FLAG" (id 1) (at 366.395 146.05 0))
    (property "Footprint" "" (id 2) (at 366.395 151.765 0)
      (effects (font (size 1.27 1.27)) hide)
    )
    (property "Datasheet" "~" (id 3) (at 366.395 151.765 0)
      (effects (font (size 1.27 1.27)) hide)
    )
    (pin "1")
  )

  (symbol (lib_id "sa800u-baseboard-hw:C_22u_0603") (at 347.345 153.035 270) (unit 1)
    (in_bom yes) (on_board yes) (fields_autoplaced)
    (property "Reference" "C135" (id 0) (at 350.393 154.3113 90)
      (effects (font (size 1.524 1.524)) (justify left))
    )
    (property "Value" "C_22u_0603" (id 1) (at 343.535 153.035 0)
      (effects (font (size 1.524 1.524)) hide)
    )
    (property "Footprint" "sa800u-baseboard-hw-footprints:C_0603_1608Metric" (id 2) (at 352.425 158.115 0)
      (effects (font (size 1.524 1.524)) (justify left) hide)
    )
    (property "Datasheet" " " (id 3) (at 347.345 153.035 0)
      (effects (font (size 1.27 1.27)) hide)
    )
    (property "Manufacturer" "Murata" (id 4) (at 357.505 158.115 0)
      (effects (font (size 1.524 1.524)) (justify left) hide)
    )
    (property "MPN" "GRM188R60J226MEA0D" (id 5) (at 354.965 158.115 0)
      (effects (font (size 1.524 1.524)) (justify left) hide)
    )
    (property "Val" "22u" (id 6) (at 350.393 157.4862 90)
      (effects (font (size 1.27 1.27)) (justify left))
    )
    (property "License" "Apache-2.0" (id 7) (at 324.485 173.355 0)
      (effects (font (size 1.27 1.27) (thickness 0.15)) (justify left bottom) hide)
    )
    (property "Author" "Antmicro" (id 8) (at 321.945 173.355 0)
      (effects (font (size 1.27 1.27) (thickness 0.15)) (justify left bottom) hide)
    )
    (property "Voltage" "" (id 9) (at 319.405 173.355 0)
      (effects (font (size 1.27 1.27)) (justify left bottom) hide)
    )
    (property "Dielectric" "" (id 10) (at 316.865 173.355 0)
      (effects (font (size 1.27 1.27)) (justify left bottom) hide)
    )
    (pin "1")
    (pin "2")
  )

  (symbol (lib_id "sa800u-baseboard-hw:GND") (at 347.345 158.115 0) (mirror y) (unit 1)
    (in_bom yes) (on_board yes) (fields_autoplaced)
    (property "Reference" "#PWR0230" (id 0) (at 347.345 164.465 0)
      (effects (font (size 1.27 1.27)) hide)
    )
    (property "Value" "GND" (id 1) (at 347.345 162.56 0))
    (property "Footprint" "" (id 2) (at 347.345 158.115 0)
      (effects (font (size 1.27 1.27)) hide)
    )
    (property "Datasheet" "" (id 3) (at 347.345 158.115 0)
      (effects (font (size 1.27 1.27)) hide)
    )
    (property "Author" "Antmicro" (id 4) (at 338.455 165.735 0)
      (effects (font (size 1.27 1.27) (thickness 0.15)) (justify left bottom) hide)
    )
    (property "License" "Apache-2.0" (id 5) (at 338.455 168.275 0)
      (effects (font (size 1.27 1.27) (thickness 0.15)) (justify left bottom) hide)
    )
    (pin "1")
  )

  (symbol (lib_id "sa800u-baseboard-hw:GND") (at 280.67 165.1 0) (mirror y) (unit 1)
    (in_bom yes) (on_board yes) (fields_autoplaced)
    (property "Reference" "#PWR0218" (id 0) (at 280.67 171.45 0)
      (effects (font (size 1.27 1.27)) hide)
    )
    (property "Value" "GND" (id 1) (at 280.67 170.18 0))
    (property "Footprint" "" (id 2) (at 280.67 165.1 0)
      (effects (font (size 1.27 1.27)) hide)
    )
    (property "Datasheet" "" (id 3) (at 280.67 165.1 0)
      (effects (font (size 1.27 1.27)) hide)
    )
    (property "Author" "Antmicro" (id 4) (at 271.78 172.72 0)
      (effects (font (size 1.27 1.27) (thickness 0.15)) (justify left bottom) hide)
    )
    (property "License" "Apache-2.0" (id 5) (at 271.78 175.26 0)
      (effects (font (size 1.27 1.27) (thickness 0.15)) (justify left bottom) hide)
    )
    (pin "1")
  )

  (symbol (lib_id "sa800u-baseboard-hw:GND") (at 293.37 167.64 0) (mirror y) (unit 1)
    (in_bom yes) (on_board yes) (fields_autoplaced)
    (property "Reference" "#PWR0222" (id 0) (at 293.37 173.99 0)
      (effects (font (size 1.27 1.27)) hide)
    )
    (property "Value" "GND" (id 1) (at 293.37 172.72 0))
    (property "Footprint" "" (id 2) (at 293.37 167.64 0)
      (effects (font (size 1.27 1.27)) hide)
    )
    (property "Datasheet" "" (id 3) (at 293.37 167.64 0)
      (effects (font (size 1.27 1.27)) hide)
    )
    (property "Author" "Antmicro" (id 4) (at 284.48 175.26 0)
      (effects (font (size 1.27 1.27) (thickness 0.15)) (justify left bottom) hide)
    )
    (property "License" "Apache-2.0" (id 5) (at 284.48 177.8 0)
      (effects (font (size 1.27 1.27) (thickness 0.15)) (justify left bottom) hide)
    )
    (pin "1")
  )

  (symbol (lib_id "sa800u-baseboard-hw:AP62301WU-7") (at 294.64 186.69 0) (unit 1)
    (in_bom yes) (on_board yes) (fields_autoplaced)
    (property "Reference" "U20" (id 0) (at 304.8 179.07 0))
    (property "Value" "AP62301WU-7" (id 1) (at 304.8 181.61 0))
    (property "Footprint" "sa800u-baseboard-hw-footprints:AP62301WU-7-TSOT23-6" (id 2) (at 293.37 203.2 0)
      (effects (font (size 1.27 1.27)) hide)
    )
    (property "Datasheet" "https://www.diodes.com/assets/Datasheets/AP62300_AP62301_AP62300T.pdf" (id 3) (at 293.37 195.58 0)
      (effects (font (size 1.27 1.27)) hide)
    )
    (property "MPN" "AP62301WU-7" (id 4) (at 293.37 200.66 0)
      (effects (font (size 1.27 1.27)) hide)
    )
    (property "Manufacturer" "Diodes Incorporated" (id 5) (at 293.37 198.12 0)
      (effects (font (size 1.27 1.27)) hide)
    )
    (property "Author" "Antmicro" (id 6) (at 330.2 204.47 0)
      (effects (font (size 1.27 1.27) (thickness 0.15)) (justify left bottom) hide)
    )
    (property "License" "Apache-2.0" (id 7) (at 330.2 207.01 0)
      (effects (font (size 1.27 1.27) (thickness 0.15)) (justify left bottom) hide)
    )
    (pin "1")
    (pin "2")
    (pin "3")
    (pin "4")
    (pin "5")
    (pin "6")
  )

  (symbol (lib_id "sa800u-baseboard-hw:GND") (at 361.315 193.04 0) (mirror y) (unit 1)
    (in_bom yes) (on_board yes) (fields_autoplaced)
    (property "Reference" "#PWR0233" (id 0) (at 361.315 199.39 0)
      (effects (font (size 1.27 1.27)) hide)
    )
    (property "Value" "GND" (id 1) (at 361.315 198.12 0))
    (property "Footprint" "" (id 2) (at 361.315 193.04 0)
      (effects (font (size 1.27 1.27)) hide)
    )
    (property "Datasheet" "" (id 3) (at 361.315 193.04 0)
      (effects (font (size 1.27 1.27)) hide)
    )
    (property "Author" "Antmicro" (id 4) (at 352.425 200.66 0)
      (effects (font (size 1.27 1.27) (thickness 0.15)) (justify left bottom) hide)
    )
    (property "License" "Apache-2.0" (id 5) (at 352.425 203.2 0)
      (effects (font (size 1.27 1.27) (thickness 0.15)) (justify left bottom) hide)
    )
    (pin "1")
  )

  (symbol (lib_id "sa800u-baseboard-hw:C_22u_0603") (at 280.67 197.485 270) (unit 1)
    (in_bom yes) (on_board yes) (fields_autoplaced)
    (property "Reference" "C129" (id 0) (at 283.083 198.7613 90)
      (effects (font (size 1.524 1.524)) (justify left))
    )
    (property "Value" "C_22u_0603" (id 1) (at 276.86 197.485 0)
      (effects (font (size 1.524 1.524)) hide)
    )
    (property "Footprint" "sa800u-baseboard-hw-footprints:C_0603_1608Metric" (id 2) (at 285.75 202.565 0)
      (effects (font (size 1.524 1.524)) (justify left) hide)
    )
    (property "Datasheet" " " (id 3) (at 280.67 197.485 0)
      (effects (font (size 1.27 1.27)) hide)
    )
    (property "Manufacturer" "Murata" (id 4) (at 290.83 202.565 0)
      (effects (font (size 1.524 1.524)) (justify left) hide)
    )
    (property "MPN" "GRM188R60J226MEA0D" (id 5) (at 288.29 202.565 0)
      (effects (font (size 1.524 1.524)) (justify left) hide)
    )
    (property "Val" "22u" (id 6) (at 283.083 201.9362 90)
      (effects (font (size 1.27 1.27)) (justify left))
    )
    (property "License" "Apache-2.0" (id 7) (at 257.81 217.805 0)
      (effects (font (size 1.27 1.27) (thickness 0.15)) (justify left bottom) hide)
    )
    (property "Author" "Antmicro" (id 8) (at 255.27 217.805 0)
      (effects (font (size 1.27 1.27) (thickness 0.15)) (justify left bottom) hide)
    )
    (property "Voltage" "" (id 9) (at 252.73 217.805 0)
      (effects (font (size 1.27 1.27)) (justify left bottom) hide)
    )
    (property "Dielectric" "" (id 10) (at 250.19 217.805 0)
      (effects (font (size 1.27 1.27)) (justify left bottom) hide)
    )
    (pin "1")
    (pin "2")
  )

  (symbol (lib_id "sa800u-baseboard-hw:GND") (at 280.67 202.565 0) (mirror y) (unit 1)
    (in_bom yes) (on_board yes) (fields_autoplaced)
    (property "Reference" "#PWR0219" (id 0) (at 280.67 208.915 0)
      (effects (font (size 1.27 1.27)) hide)
    )
    (property "Value" "GND" (id 1) (at 280.67 207.01 0))
    (property "Footprint" "" (id 2) (at 280.67 202.565 0)
      (effects (font (size 1.27 1.27)) hide)
    )
    (property "Datasheet" "" (id 3) (at 280.67 202.565 0)
      (effects (font (size 1.27 1.27)) hide)
    )
    (property "Author" "Antmicro" (id 4) (at 271.78 210.185 0)
      (effects (font (size 1.27 1.27) (thickness 0.15)) (justify left bottom) hide)
    )
    (property "License" "Apache-2.0" (id 5) (at 271.78 212.725 0)
      (effects (font (size 1.27 1.27) (thickness 0.15)) (justify left bottom) hide)
    )
    (pin "1")
  )

  (symbol (lib_id "sa800u-baseboard-hw:C_22u_0603") (at 361.315 222.885 270) (unit 1)
    (in_bom yes) (on_board yes) (fields_autoplaced)
    (property "Reference" "C140" (id 0) (at 364.49 224.1613 90)
      (effects (font (size 1.524 1.524)) (justify left))
    )
    (property "Value" "C_22u_0603" (id 1) (at 357.505 222.885 0)
      (effects (font (size 1.524 1.524)) hide)
    )
    (property "Footprint" "sa800u-baseboard-hw-footprints:C_0603_1608Metric" (id 2) (at 366.395 227.965 0)
      (effects (font (size 1.524 1.524)) (justify left) hide)
    )
    (property "Datasheet" " " (id 3) (at 361.315 222.885 0)
      (effects (font (size 1.27 1.27)) hide)
    )
    (property "Manufacturer" "Murata" (id 4) (at 371.475 227.965 0)
      (effects (font (size 1.524 1.524)) (justify left) hide)
    )
    (property "MPN" "GRM188R60J226MEA0D" (id 5) (at 368.935 227.965 0)
      (effects (font (size 1.524 1.524)) (justify left) hide)
    )
    (property "Val" "22u" (id 6) (at 364.49 227.3362 90)
      (effects (font (size 1.27 1.27)) (justify left))
    )
    (property "License" "Apache-2.0" (id 7) (at 338.455 243.205 0)
      (effects (font (size 1.27 1.27) (thickness 0.15)) (justify left bottom) hide)
    )
    (property "Author" "Antmicro" (id 8) (at 335.915 243.205 0)
      (effects (font (size 1.27 1.27) (thickness 0.15)) (justify left bottom) hide)
    )
    (property "Voltage" "" (id 9) (at 333.375 243.205 0)
      (effects (font (size 1.27 1.27)) (justify left bottom) hide)
    )
    (property "Dielectric" "" (id 10) (at 330.835 243.205 0)
      (effects (font (size 1.27 1.27)) (justify left bottom) hide)
    )
    (pin "1")
    (pin "2")
  )

  (symbol (lib_id "sa800u-baseboard-hw:GND") (at 361.315 227.965 0) (mirror y) (unit 1)
    (in_bom yes) (on_board yes) (fields_autoplaced)
    (property "Reference" "#PWR0234" (id 0) (at 361.315 234.315 0)
      (effects (font (size 1.27 1.27)) hide)
    )
    (property "Value" "GND" (id 1) (at 361.315 232.41 0))
    (property "Footprint" "" (id 2) (at 361.315 227.965 0)
      (effects (font (size 1.27 1.27)) hide)
    )
    (property "Datasheet" "" (id 3) (at 361.315 227.965 0)
      (effects (font (size 1.27 1.27)) hide)
    )
    (property "Author" "Antmicro" (id 4) (at 352.425 235.585 0)
      (effects (font (size 1.27 1.27) (thickness 0.15)) (justify left bottom) hide)
    )
    (property "License" "Apache-2.0" (id 5) (at 352.425 238.125 0)
      (effects (font (size 1.27 1.27) (thickness 0.15)) (justify left bottom) hide)
    )
    (pin "1")
  )

  (symbol (lib_id "sa800u-baseboard-hw:C_22u_0603") (at 280.67 232.41 270) (unit 1)
    (in_bom yes) (on_board yes) (fields_autoplaced)
    (property "Reference" "C130" (id 0) (at 283.464 233.6863 90)
      (effects (font (size 1.524 1.524)) (justify left))
    )
    (property "Value" "C_22u_0603" (id 1) (at 276.86 232.41 0)
      (effects (font (size 1.524 1.524)) hide)
    )
    (property "Footprint" "sa800u-baseboard-hw-footprints:C_0603_1608Metric" (id 2) (at 285.75 237.49 0)
      (effects (font (size 1.524 1.524)) (justify left) hide)
    )
    (property "Datasheet" " " (id 3) (at 280.67 232.41 0)
      (effects (font (size 1.27 1.27)) hide)
    )
    (property "Manufacturer" "Murata" (id 4) (at 290.83 237.49 0)
      (effects (font (size 1.524 1.524)) (justify left) hide)
    )
    (property "MPN" "GRM188R60J226MEA0D" (id 5) (at 288.29 237.49 0)
      (effects (font (size 1.524 1.524)) (justify left) hide)
    )
    (property "Val" "22u" (id 6) (at 283.464 236.8612 90)
      (effects (font (size 1.27 1.27)) (justify left))
    )
    (property "License" "Apache-2.0" (id 7) (at 257.81 252.73 0)
      (effects (font (size 1.27 1.27) (thickness 0.15)) (justify left bottom) hide)
    )
    (property "Author" "Antmicro" (id 8) (at 255.27 252.73 0)
      (effects (font (size 1.27 1.27) (thickness 0.15)) (justify left bottom) hide)
    )
    (property "Voltage" "" (id 9) (at 252.73 252.73 0)
      (effects (font (size 1.27 1.27)) (justify left bottom) hide)
    )
    (property "Dielectric" "" (id 10) (at 250.19 252.73 0)
      (effects (font (size 1.27 1.27)) (justify left bottom) hide)
    )
    (pin "1")
    (pin "2")
  )

  (symbol (lib_id "sa800u-baseboard-hw:GND") (at 280.67 237.49 0) (mirror y) (unit 1)
    (in_bom yes) (on_board yes) (fields_autoplaced)
    (property "Reference" "#PWR0220" (id 0) (at 280.67 243.84 0)
      (effects (font (size 1.27 1.27)) hide)
    )
    (property "Value" "GND" (id 1) (at 280.67 242.57 0))
    (property "Footprint" "" (id 2) (at 280.67 237.49 0)
      (effects (font (size 1.27 1.27)) hide)
    )
    (property "Datasheet" "" (id 3) (at 280.67 237.49 0)
      (effects (font (size 1.27 1.27)) hide)
    )
    (property "Author" "Antmicro" (id 4) (at 271.78 245.11 0)
      (effects (font (size 1.27 1.27) (thickness 0.15)) (justify left bottom) hide)
    )
    (property "License" "Apache-2.0" (id 5) (at 271.78 247.65 0)
      (effects (font (size 1.27 1.27) (thickness 0.15)) (justify left bottom) hide)
    )
    (pin "1")
  )

  (symbol (lib_id "sa800u-baseboard-hw:AP62301WU-7") (at 294.64 151.765 0) (unit 1)
    (in_bom yes) (on_board yes) (fields_autoplaced)
    (property "Reference" "U19" (id 0) (at 304.8 143.51 0))
    (property "Value" "AP62301WU-7" (id 1) (at 304.8 146.05 0))
    (property "Footprint" "sa800u-baseboard-hw-footprints:AP62301WU-7-TSOT23-6" (id 2) (at 293.37 168.275 0)
      (effects (font (size 1.27 1.27)) hide)
    )
    (property "Datasheet" "https://www.diodes.com/assets/Datasheets/AP62300_AP62301_AP62300T.pdf" (id 3) (at 293.37 160.655 0)
      (effects (font (size 1.27 1.27)) hide)
    )
    (property "MPN" "AP62301WU-7" (id 4) (at 293.37 165.735 0)
      (effects (font (size 1.27 1.27)) hide)
    )
    (property "Manufacturer" "Diodes Incorporated" (id 5) (at 293.37 163.195 0)
      (effects (font (size 1.27 1.27)) hide)
    )
    (property "Author" "Antmicro" (id 6) (at 330.2 169.545 0)
      (effects (font (size 1.27 1.27) (thickness 0.15)) (justify left bottom) hide)
    )
    (property "License" "Apache-2.0" (id 7) (at 330.2 172.085 0)
      (effects (font (size 1.27 1.27) (thickness 0.15)) (justify left bottom) hide)
    )
    (pin "1")
    (pin "2")
    (pin "3")
    (pin "4")
    (pin "5")
    (pin "6")
  )

  (symbol (lib_id "sa800u-baseboard-hw:C_100n_0402") (at 316.23 156.845 0) (unit 1)
    (in_bom yes) (on_board yes)
    (property "Reference" "C132" (id 0) (at 322.58 155.575 0)
      (effects (font (size 1.524 1.524)))
    )
    (property "Value" "C_100n_0402" (id 1) (at 316.23 160.655 0)
      (effects (font (size 1.524 1.524)) hide)
    )
    (property "Footprint" "sa800u-baseboard-hw-footprints:C_0402_1005Metric" (id 2) (at 321.31 151.765 0)
      (effects (font (size 1.524 1.524)) (justify left) hide)
    )
    (property "Datasheet" "https://search.murata.co.jp/Ceramy/image/img/A01X/G101/ENG/GRM155R61H104KE14-01.pdf" (id 3) (at 316.23 156.845 0)
      (effects (font (size 1.27 1.27)) hide)
    )
    (property "Manufacturer" "Murata" (id 4) (at 321.31 146.685 0)
      (effects (font (size 1.524 1.524)) (justify left) hide)
    )
    (property "MPN" "GRM155R61H104KE14D" (id 5) (at 321.31 149.225 0)
      (effects (font (size 1.524 1.524)) (justify left) hide)
    )
    (property "Val" "100n" (id 6) (at 322.58 158.115 0))
    (property "License" "Apache-2.0" (id 7) (at 336.55 179.705 0)
      (effects (font (size 1.27 1.27) (thickness 0.15)) (justify left bottom) hide)
    )
    (property "Author" "Antmicro" (id 8) (at 336.55 182.245 0)
      (effects (font (size 1.27 1.27) (thickness 0.15)) (justify left bottom) hide)
    )
    (property "Voltage" "50V" (id 9) (at 336.55 184.785 0)
      (effects (font (size 1.27 1.27)) (justify left bottom) hide)
    )
    (property "Dielectric" "X5R" (id 10) (at 336.55 187.325 0)
      (effects (font (size 1.27 1.27)) (justify left bottom) hide)
    )
    (pin "1")
    (pin "2")
  )

  (symbol (lib_id "sa800u-baseboard-hw:R_31k6_0402") (at 336.55 187.96 270) (unit 1)
    (in_bom yes) (on_board yes) (fields_autoplaced)
    (property "Reference" "R137" (id 0) (at 339.09 189.23 90)
      (effects (font (size 1.524 1.524)) (justify left))
    )
    (property "Value" "R_31k6_0402" (id 1) (at 332.74 187.96 0)
      (effects (font (size 1.524 1.524)) hide)
    )
    (property "Footprint" "sa800u-baseboard-hw-footprints:R_0402_1005Metric" (id 2) (at 341.63 193.04 0)
      (effects (font (size 1.524 1.524)) (justify left) hide)
    )
    (property "Datasheet" "https://www.bourns.com/docs/product-datasheets/cr.pdf" (id 3) (at 336.55 187.96 0)
      (effects (font (size 1.27 1.27)) hide)
    )
    (property "Manufacturer" "Bourns" (id 4) (at 346.71 193.04 0)
      (effects (font (size 1.524 1.524)) (justify left) hide)
    )
    (property "MPN" "CR0402-FX-3162GLF" (id 5) (at 344.17 193.04 0)
      (effects (font (size 1.524 1.524)) (justify left) hide)
    )
    (property "Val" "31k6" (id 6) (at 339.09 192.4049 90)
      (effects (font (size 1.27 1.27)) (justify left))
    )
    (property "License" "Apache-2.0" (id 7) (at 311.15 208.28 0)
      (effects (font (size 1.27 1.27) (thickness 0.15)) (justify left bottom) hide)
    )
    (property "Author" "Antmicro" (id 8) (at 308.61 208.28 0)
      (effects (font (size 1.27 1.27) (thickness 0.15)) (justify left bottom) hide)
    )
    (property "Tolerance" "1%" (id 9) (at 326.39 208.28 0)
      (effects (font (size 1.27 1.27)) (justify left bottom) hide)
    )
    (pin "1")
    (pin "2")
  )

  (symbol (lib_id "sa800u-baseboard-hw:GND") (at 336.55 205.74 0) (mirror y) (unit 1)
    (in_bom yes) (on_board yes) (fields_autoplaced)
    (property "Reference" "#PWR0228" (id 0) (at 336.55 212.09 0)
      (effects (font (size 1.27 1.27)) hide)
    )
    (property "Value" "GND" (id 1) (at 336.55 210.82 0))
    (property "Footprint" "" (id 2) (at 336.55 205.74 0)
      (effects (font (size 1.27 1.27)) hide)
    )
    (property "Datasheet" "" (id 3) (at 336.55 205.74 0)
      (effects (font (size 1.27 1.27)) hide)
    )
    (property "Author" "Antmicro" (id 4) (at 327.66 213.36 0)
      (effects (font (size 1.27 1.27) (thickness 0.15)) (justify left bottom) hide)
    )
    (property "License" "Apache-2.0" (id 5) (at 327.66 215.9 0)
      (effects (font (size 1.27 1.27) (thickness 0.15)) (justify left bottom) hide)
    )
    (pin "1")
  )

  (symbol (lib_id "sa800u-baseboard-hw:C_22u_0603") (at 361.95 153.035 270) (unit 1)
    (in_bom yes) (on_board yes) (fields_autoplaced)
    (property "Reference" "C141" (id 0) (at 364.49 154.3113 90)
      (effects (font (size 1.524 1.524)) (justify left))
    )
    (property "Value" "C_22u_0603" (id 1) (at 358.14 153.035 0)
      (effects (font (size 1.524 1.524)) hide)
    )
    (property "Footprint" "sa800u-baseboard-hw-footprints:C_0603_1608Metric" (id 2) (at 367.03 158.115 0)
      (effects (font (size 1.524 1.524)) (justify left) hide)
    )
    (property "Datasheet" " " (id 3) (at 361.95 153.035 0)
      (effects (font (size 1.27 1.27)) hide)
    )
    (property "Manufacturer" "Murata" (id 4) (at 372.11 158.115 0)
      (effects (font (size 1.524 1.524)) (justify left) hide)
    )
    (property "MPN" "GRM188R60J226MEA0D" (id 5) (at 369.57 158.115 0)
      (effects (font (size 1.524 1.524)) (justify left) hide)
    )
    (property "Val" "22u" (id 6) (at 364.49 157.4862 90)
      (effects (font (size 1.27 1.27)) (justify left))
    )
    (property "License" "Apache-2.0" (id 7) (at 339.09 173.355 0)
      (effects (font (size 1.27 1.27) (thickness 0.15)) (justify left bottom) hide)
    )
    (property "Author" "Antmicro" (id 8) (at 336.55 173.355 0)
      (effects (font (size 1.27 1.27) (thickness 0.15)) (justify left bottom) hide)
    )
    (property "Voltage" "" (id 9) (at 334.01 173.355 0)
      (effects (font (size 1.27 1.27)) (justify left bottom) hide)
    )
    (property "Dielectric" "" (id 10) (at 331.47 173.355 0)
      (effects (font (size 1.27 1.27)) (justify left bottom) hide)
    )
    (pin "1")
    (pin "2")
  )

  (symbol (lib_name "L_2u2_6.1A_XEL4030_3") (lib_id "sa800u-baseboard-hw:L_2u2_6.1A_XEL4030") (at 326.39 186.69 0) (unit 1)
    (in_bom yes) (on_board yes) (fields_autoplaced)
    (property "Reference" "L27" (id 0) (at 328.93 181.61 0))
    (property "Value" "L_2u2_6.1A_XEL4030" (id 1) (at 328.93 181.61 0)
      (effects (font (size 1.27 1.27)) hide)
    )
    (property "Footprint" "sa800u-baseboard-hw-footprints:L_Coilcraft_XEL4030" (id 2) (at 346.71 180.34 0)
      (effects (font (size 1.524 1.524)) hide)
    )
    (property "Datasheet" "https://www.coilcraft.com/getmedia/8245f050-f190-4295-8c41-7c03d662ee3d/xel4030.pdf" (id 3) (at 327.787 185.928 0)
      (effects (font (size 1.524 1.524)) hide)
    )
    (property "MPN" "XEL4030-222MEC" (id 4) (at 331.47 173.99 0)
      (effects (font (size 1.27 1.27)) hide)
    )
    (property "Manufacturer" "Coilcraft" (id 5) (at 334.01 171.45 0)
      (effects (font (size 1.27 1.27)) hide)
    )
    (property "Val" "2u2/6.1A" (id 6) (at 328.93 184.15 0))
    (property "MaxCur" "6.1A" (id 7) (at 328.295 175.895 0)
      (effects (font (size 1.27 1.27)) hide)
    )
    (property "Size" "4x4" (id 8) (at 329.565 178.435 0)
      (effects (font (size 1.27 1.27)) hide)
    )
    (property "ISat" "" (id 9) (at 340.36 203.2 0)
      (effects (font (size 1.27 1.27)) (justify left) hide)
    )
    (property "IMax" "" (id 10) (at 340.36 207.01 0)
      (effects (font (size 1.27 1.27) (thickness 0.15)) (justify left bottom) hide)
    )
    (property "Author" "Antmicro" (id 11) (at 340.36 212.09 0)
      (effects (font (size 1.27 1.27) (thickness 0.15)) (justify left bottom) hide)
    )
    (property "License" "Apache-2.0" (id 12) (at 340.36 214.63 0)
      (effects (font (size 1.27 1.27) (thickness 0.15)) (justify left bottom) hide)
    )
    (pin "1")
    (pin "2")
  )

  (symbol (lib_id "sa800u-baseboard-hw:C_22u_0603") (at 280.67 160.02 270) (unit 1)
    (in_bom yes) (on_board yes) (fields_autoplaced)
    (property "Reference" "C128" (id 0) (at 278.13 161.2963 90)
      (effects (font (size 1.524 1.524)) (justify right))
    )
    (property "Value" "C_22u_0603" (id 1) (at 276.86 160.02 0)
      (effects (font (size 1.524 1.524)) hide)
    )
    (property "Footprint" "sa800u-baseboard-hw-footprints:C_0603_1608Metric" (id 2) (at 285.75 165.1 0)
      (effects (font (size 1.524 1.524)) (justify left) hide)
    )
    (property "Datasheet" " " (id 3) (at 280.67 160.02 0)
      (effects (font (size 1.27 1.27)) hide)
    )
    (property "Manufacturer" "Murata" (id 4) (at 290.83 165.1 0)
      (effects (font (size 1.524 1.524)) (justify left) hide)
    )
    (property "MPN" "GRM188R60J226MEA0D" (id 5) (at 288.29 165.1 0)
      (effects (font (size 1.524 1.524)) (justify left) hide)
    )
    (property "Val" "22u" (id 6) (at 278.13 164.4712 90)
      (effects (font (size 1.27 1.27)) (justify right))
    )
    (property "License" "Apache-2.0" (id 7) (at 257.81 180.34 0)
      (effects (font (size 1.27 1.27) (thickness 0.15)) (justify left bottom) hide)
    )
    (property "Author" "Antmicro" (id 8) (at 255.27 180.34 0)
      (effects (font (size 1.27 1.27) (thickness 0.15)) (justify left bottom) hide)
    )
    (property "Voltage" "" (id 9) (at 252.73 180.34 0)
      (effects (font (size 1.27 1.27)) (justify left bottom) hide)
    )
    (property "Dielectric" "" (id 10) (at 250.19 180.34 0)
      (effects (font (size 1.27 1.27)) (justify left bottom) hide)
    )
    (pin "1")
    (pin "2")
  )

  (symbol (lib_id "sa800u-baseboard-hw:GND") (at 336.55 240.665 0) (mirror y) (unit 1)
    (in_bom yes) (on_board yes) (fields_autoplaced)
    (property "Reference" "#PWR0229" (id 0) (at 336.55 247.015 0)
      (effects (font (size 1.27 1.27)) hide)
    )
    (property "Value" "GND" (id 1) (at 336.55 245.11 0))
    (property "Footprint" "" (id 2) (at 336.55 240.665 0)
      (effects (font (size 1.27 1.27)) hide)
    )
    (property "Datasheet" "" (id 3) (at 336.55 240.665 0)
      (effects (font (size 1.27 1.27)) hide)
    )
    (property "Author" "Antmicro" (id 4) (at 327.66 248.285 0)
      (effects (font (size 1.27 1.27) (thickness 0.15)) (justify left bottom) hide)
    )
    (property "License" "Apache-2.0" (id 5) (at 327.66 250.825 0)
      (effects (font (size 1.27 1.27) (thickness 0.15)) (justify left bottom) hide)
    )
    (pin "1")
  )

  (symbol (lib_id "sa800u-baseboard-hw:L_2u2_6.1A_XEL4030") (at 327.66 221.615 0) (unit 1)
    (in_bom yes) (on_board yes) (fields_autoplaced)
    (property "Reference" "L28" (id 0) (at 330.2 215.9 0))
    (property "Value" "L_2u2_6.1A_XEL4030" (id 1) (at 330.2 215.9 0)
      (effects (font (size 1.27 1.27)) hide)
    )
    (property "Footprint" "sa800u-baseboard-hw-footprints:L_Coilcraft_XEL4030" (id 2) (at 347.98 215.265 0)
      (effects (font (size 1.524 1.524)) hide)
    )
    (property "Datasheet" "https://www.coilcraft.com/getmedia/8245f050-f190-4295-8c41-7c03d662ee3d/xel4030.pdf" (id 3) (at 329.057 220.853 0)
      (effects (font (size 1.524 1.524)) hide)
    )
    (property "MPN" "XEL4030-222MEC" (id 4) (at 332.74 208.915 0)
      (effects (font (size 1.27 1.27)) hide)
    )
    (property "Manufacturer" "Coilcraft" (id 5) (at 335.28 206.375 0)
      (effects (font (size 1.27 1.27)) hide)
    )
    (property "Val" "2u2/6.1A" (id 6) (at 330.2 218.44 0))
    (property "MaxCur" "6.1A" (id 7) (at 329.565 210.82 0)
      (effects (font (size 1.27 1.27)) hide)
    )
    (property "Size" "4x4" (id 8) (at 330.835 213.36 0)
      (effects (font (size 1.27 1.27)) hide)
    )
    (property "ISat" "" (id 9) (at 341.63 238.125 0)
      (effects (font (size 1.27 1.27)) (justify left) hide)
    )
    (property "IMax" "" (id 10) (at 341.63 241.935 0)
      (effects (font (size 1.27 1.27) (thickness 0.15)) (justify left bottom) hide)
    )
    (property "Author" "Antmicro" (id 11) (at 341.63 247.015 0)
      (effects (font (size 1.27 1.27) (thickness 0.15)) (justify left bottom) hide)
    )
    (property "License" "Apache-2.0" (id 12) (at 341.63 249.555 0)
      (effects (font (size 1.27 1.27) (thickness 0.15)) (justify left bottom) hide)
    )
    (pin "1")
    (pin "2")
  )

  (symbol (lib_id "sa800u-baseboard-hw:R_20k_0402") (at 336.55 240.665 90) (unit 1)
    (in_bom yes) (on_board yes) (fields_autoplaced)
    (property "Reference" "R140" (id 0) (at 339.09 236.855 90)
      (effects (font (size 1.524 1.524)) (justify right))
    )
    (property "Value" "R_20k_0402" (id 1) (at 340.36 240.665 0)
      (effects (font (size 1.524 1.524)) hide)
    )
    (property "Footprint" "sa800u-baseboard-hw-footprints:R_0402_1005Metric" (id 2) (at 331.47 235.585 0)
      (effects (font (size 1.524 1.524)) (justify left) hide)
    )
    (property "Datasheet" "https://www.bourns.com/docs/product-datasheets/cr.pdf" (id 3) (at 336.55 240.665 0)
      (effects (font (size 1.27 1.27)) hide)
    )
    (property "Manufacturer" "Bourns" (id 4) (at 326.39 235.585 0)
      (effects (font (size 1.524 1.524)) (justify left) hide)
    )
    (property "MPN" "CR0402-FX-2002GLF" (id 5) (at 328.93 235.585 0)
      (effects (font (size 1.524 1.524)) (justify left) hide)
    )
    (property "Val" "20k" (id 6) (at 339.09 240.0299 90)
      (effects (font (size 1.27 1.27)) (justify right))
    )
    (property "License" "Apache-2.0" (id 7) (at 361.95 220.345 0)
      (effects (font (size 1.27 1.27) (thickness 0.15)) (justify left bottom) hide)
    )
    (property "Author" "Antmicro" (id 8) (at 364.49 220.345 0)
      (effects (font (size 1.27 1.27) (thickness 0.15)) (justify left bottom) hide)
    )
    (property "Tolerance" "1%" (id 9) (at 346.71 220.345 0)
      (effects (font (size 1.27 1.27)) (justify left bottom) hide)
    )
    (pin "1")
    (pin "2")
  )

  (symbol (lib_id "sa800u-baseboard-hw:R_20k_0402") (at 336.55 170.815 90) (unit 1)
    (in_bom yes) (on_board yes) (fields_autoplaced)
    (property "Reference" "R136" (id 0) (at 339.09 167.005 90)
      (effects (font (size 1.524 1.524)) (justify right))
    )
    (property "Value" "R_20k_0402" (id 1) (at 340.36 170.815 0)
      (effects (font (size 1.524 1.524)) hide)
    )
    (property "Footprint" "sa800u-baseboard-hw-footprints:R_0402_1005Metric" (id 2) (at 331.47 165.735 0)
      (effects (font (size 1.524 1.524)) (justify left) hide)
    )
    (property "Datasheet" "https://www.bourns.com/docs/product-datasheets/cr.pdf" (id 3) (at 336.55 170.815 0)
      (effects (font (size 1.27 1.27)) hide)
    )
    (property "Manufacturer" "Bourns" (id 4) (at 326.39 165.735 0)
      (effects (font (size 1.524 1.524)) (justify left) hide)
    )
    (property "MPN" "CR0402-FX-2002GLF" (id 5) (at 328.93 165.735 0)
      (effects (font (size 1.524 1.524)) (justify left) hide)
    )
    (property "Val" "20k" (id 6) (at 339.09 170.1799 90)
      (effects (font (size 1.27 1.27)) (justify right))
    )
    (property "License" "Apache-2.0" (id 7) (at 361.95 150.495 0)
      (effects (font (size 1.27 1.27) (thickness 0.15)) (justify left bottom) hide)
    )
    (property "Author" "Antmicro" (id 8) (at 364.49 150.495 0)
      (effects (font (size 1.27 1.27) (thickness 0.15)) (justify left bottom) hide)
    )
    (property "Tolerance" "1%" (id 9) (at 346.71 150.495 0)
      (effects (font (size 1.27 1.27)) (justify left bottom) hide)
    )
    (pin "1")
    (pin "2")
  )

  (symbol (lib_id "sa800u-baseboard-hw:R_52k3_0402") (at 364.49 71.501 270) (unit 1)
    (in_bom yes) (on_board yes) (fields_autoplaced)
    (property "Reference" "R141" (id 0) (at 367.03 72.771 90)
      (effects (font (size 1.524 1.524)) (justify left))
    )
    (property "Value" "R_52k3_0402" (id 1) (at 360.68 71.501 0)
      (effects (font (size 1.524 1.524)) hide)
    )
    (property "Footprint" "sa800u-baseboard-hw-footprints:R_0402_1005Metric" (id 2) (at 369.57 76.581 0)
      (effects (font (size 1.524 1.524)) (justify left) hide)
    )
    (property "Datasheet" "https://www.bourns.com/docs/product-datasheets/cr.pdf" (id 3) (at 364.49 71.501 0)
      (effects (font (size 1.27 1.27)) hide)
    )
    (property "Manufacturer" "Bourns" (id 4) (at 374.65 76.581 0)
      (effects (font (size 1.524 1.524)) (justify left) hide)
    )
    (property "MPN" "CR0402-FX-5232GLF" (id 5) (at 372.11 76.581 0)
      (effects (font (size 1.524 1.524)) (justify left) hide)
    )
    (property "Val" "52k3" (id 6) (at 367.03 75.9459 90)
      (effects (font (size 1.27 1.27)) (justify left))
    )
    (property "License" "Apache-2.0" (id 7) (at 339.09 91.821 0)
      (effects (font (size 1.27 1.27) (thickness 0.15)) (justify left bottom) hide)
    )
    (property "Author" "Antmicro" (id 8) (at 336.55 91.821 0)
      (effects (font (size 1.27 1.27) (thickness 0.15)) (justify left bottom) hide)
    )
    (property "Tolerance" "1%" (id 9) (at 354.33 91.821 0)
      (effects (font (size 1.27 1.27)) (justify left bottom) hide)
    )
    (pin "1")
    (pin "2")
  )

  (symbol (lib_id "sa800u-baseboard-hw:R_10k_0402") (at 364.49 81.661 270) (unit 1)
    (in_bom yes) (on_board yes) (fields_autoplaced)
    (property "Reference" "R142" (id 0) (at 367.03 82.931 90)
      (effects (font (size 1.524 1.524)) (justify left))
    )
    (property "Value" "R_10k_0402" (id 1) (at 360.68 81.661 0)
      (effects (font (size 1.524 1.524)) hide)
    )
    (property "Footprint" "sa800u-baseboard-hw-footprints:R_0402_1005Metric" (id 2) (at 369.57 86.741 0)
      (effects (font (size 1.524 1.524)) (justify left) hide)
    )
    (property "Datasheet" "https://www.bourns.com/docs/product-datasheets/cr.pdf" (id 3) (at 364.49 81.661 0)
      (effects (font (size 1.27 1.27)) hide)
    )
    (property "Manufacturer" "Bourns" (id 4) (at 374.65 86.741 0)
      (effects (font (size 1.524 1.524)) (justify left) hide)
    )
    (property "MPN" "CR0402-FX-1002GLF" (id 5) (at 372.11 86.741 0)
      (effects (font (size 1.524 1.524)) (justify left) hide)
    )
    (property "Val" "10k" (id 6) (at 367.03 86.1059 90)
      (effects (font (size 1.27 1.27)) (justify left))
    )
    (property "License" "Apache-2.0" (id 7) (at 339.09 101.981 0)
      (effects (font (size 1.27 1.27) (thickness 0.15)) (justify left bottom) hide)
    )
    (property "Author" "Antmicro" (id 8) (at 336.55 101.981 0)
      (effects (font (size 1.27 1.27) (thickness 0.15)) (justify left bottom) hide)
    )
    (property "Tolerance" "1%" (id 9) (at 354.33 101.981 0)
      (effects (font (size 1.27 1.27)) (justify left bottom) hide)
    )
    (pin "1")
    (pin "2")
  )

  (symbol (lib_id "sa800u-baseboard-hw:GND") (at 364.49 86.741 0) (unit 1)
    (in_bom yes) (on_board yes) (fields_autoplaced)
    (property "Reference" "#PWR0236" (id 0) (at 364.49 93.091 0)
      (effects (font (size 1.27 1.27)) hide)
    )
    (property "Value" "GND" (id 1) (at 364.49 91.186 0))
    (property "Footprint" "" (id 2) (at 364.49 86.741 0)
      (effects (font (size 1.27 1.27)) hide)
    )
    (property "Datasheet" "" (id 3) (at 364.49 86.741 0)
      (effects (font (size 1.27 1.27)) hide)
    )
    (property "Author" "Antmicro" (id 4) (at 373.38 94.361 0)
      (effects (font (size 1.27 1.27) (thickness 0.15)) (justify left bottom) hide)
    )
    (property "License" "Apache-2.0" (id 5) (at 373.38 96.901 0)
      (effects (font (size 1.27 1.27) (thickness 0.15)) (justify left bottom) hide)
    )
    (pin "1")
  )

  (symbol (lib_id "sa800u-baseboard-hw:R_10k_0402") (at 336.55 198.12 270) (unit 1)
    (in_bom yes) (on_board yes) (fields_autoplaced)
    (property "Reference" "R138" (id 0) (at 339.09 199.39 90)
      (effects (font (size 1.524 1.524)) (justify left))
    )
    (property "Value" "R_10k_0402" (id 1) (at 332.74 198.12 0)
      (effects (font (size 1.524 1.524)) hide)
    )
    (property "Footprint" "sa800u-baseboard-hw-footprints:R_0402_1005Metric" (id 2) (at 341.63 203.2 0)
      (effects (font (size 1.524 1.524)) (justify left) hide)
    )
    (property "Datasheet" "https://www.bourns.com/docs/product-datasheets/cr.pdf" (id 3) (at 336.55 198.12 0)
      (effects (font (size 1.27 1.27)) hide)
    )
    (property "Manufacturer" "Bourns" (id 4) (at 346.71 203.2 0)
      (effects (font (size 1.524 1.524)) (justify left) hide)
    )
    (property "MPN" "CR0402-FX-1002GLF" (id 5) (at 344.17 203.2 0)
      (effects (font (size 1.524 1.524)) (justify left) hide)
    )
    (property "Val" "10k" (id 6) (at 339.09 202.5649 90)
      (effects (font (size 1.27 1.27)) (justify left))
    )
    (property "License" "Apache-2.0" (id 7) (at 311.15 218.44 0)
      (effects (font (size 1.27 1.27) (thickness 0.15)) (justify left bottom) hide)
    )
    (property "Author" "Antmicro" (id 8) (at 308.61 218.44 0)
      (effects (font (size 1.27 1.27) (thickness 0.15)) (justify left bottom) hide)
    )
    (property "Tolerance" "1%" (id 9) (at 326.39 218.44 0)
      (effects (font (size 1.27 1.27)) (justify left bottom) hide)
    )
    (pin "1")
    (pin "2")
  )

  (symbol (lib_id "sa800u-baseboard-hw:GND") (at 336.55 170.815 0) (mirror y) (unit 1)
    (in_bom yes) (on_board yes) (fields_autoplaced)
    (property "Reference" "#PWR0227" (id 0) (at 336.55 177.165 0)
      (effects (font (size 1.27 1.27)) hide)
    )
    (property "Value" "GND" (id 1) (at 336.55 175.26 0))
    (property "Footprint" "" (id 2) (at 336.55 170.815 0)
      (effects (font (size 1.27 1.27)) hide)
    )
    (property "Datasheet" "" (id 3) (at 336.55 170.815 0)
      (effects (font (size 1.27 1.27)) hide)
    )
    (property "Author" "Antmicro" (id 4) (at 327.66 178.435 0)
      (effects (font (size 1.27 1.27) (thickness 0.15)) (justify left bottom) hide)
    )
    (property "License" "Apache-2.0" (id 5) (at 327.66 180.975 0)
      (effects (font (size 1.27 1.27) (thickness 0.15)) (justify left bottom) hide)
    )
    (pin "1")
  )

  (symbol (lib_id "sa800u-baseboard-hw:GND") (at 347.345 193.04 0) (mirror y) (unit 1)
    (in_bom yes) (on_board yes) (fields_autoplaced)
    (property "Reference" "#PWR0231" (id 0) (at 347.345 199.39 0)
      (effects (font (size 1.27 1.27)) hide)
    )
    (property "Value" "GND" (id 1) (at 347.345 198.12 0))
    (property "Footprint" "" (id 2) (at 347.345 193.04 0)
      (effects (font (size 1.27 1.27)) hide)
    )
    (property "Datasheet" "" (id 3) (at 347.345 193.04 0)
      (effects (font (size 1.27 1.27)) hide)
    )
    (property "Author" "Antmicro" (id 4) (at 338.455 200.66 0)
      (effects (font (size 1.27 1.27) (thickness 0.15)) (justify left bottom) hide)
    )
    (property "License" "Apache-2.0" (id 5) (at 338.455 203.2 0)
      (effects (font (size 1.27 1.27) (thickness 0.15)) (justify left bottom) hide)
    )
    (pin "1")
  )

  (symbol (lib_id "sa800u-baseboard-hw:GND") (at 293.37 202.565 0) (mirror y) (unit 1)
    (in_bom yes) (on_board yes) (fields_autoplaced)
    (property "Reference" "#PWR0223" (id 0) (at 293.37 208.915 0)
      (effects (font (size 1.27 1.27)) hide)
    )
    (property "Value" "GND" (id 1) (at 293.37 207.01 0))
    (property "Footprint" "" (id 2) (at 293.37 202.565 0)
      (effects (font (size 1.27 1.27)) hide)
    )
    (property "Datasheet" "" (id 3) (at 293.37 202.565 0)
      (effects (font (size 1.27 1.27)) hide)
    )
    (property "Author" "Antmicro" (id 4) (at 284.48 210.185 0)
      (effects (font (size 1.27 1.27) (thickness 0.15)) (justify left bottom) hide)
    )
    (property "License" "Apache-2.0" (id 5) (at 284.48 212.725 0)
      (effects (font (size 1.27 1.27) (thickness 0.15)) (justify left bottom) hide)
    )
    (pin "1")
  )

  (symbol (lib_id "sa800u-baseboard-hw:AP62301WU-7") (at 294.64 221.615 0) (unit 1)
    (in_bom yes) (on_board yes) (fields_autoplaced)
    (property "Reference" "U21" (id 0) (at 304.8 213.36 0))
    (property "Value" "AP62301WU-7" (id 1) (at 304.8 215.9 0))
    (property "Footprint" "sa800u-baseboard-hw-footprints:AP62301WU-7-TSOT23-6" (id 2) (at 293.37 238.125 0)
      (effects (font (size 1.27 1.27)) hide)
    )
    (property "Datasheet" "https://www.diodes.com/assets/Datasheets/AP62300_AP62301_AP62300T.pdf" (id 3) (at 293.37 230.505 0)
      (effects (font (size 1.27 1.27)) hide)
    )
    (property "MPN" "AP62301WU-7" (id 4) (at 293.37 235.585 0)
      (effects (font (size 1.27 1.27)) hide)
    )
    (property "Manufacturer" "Diodes Incorporated" (id 5) (at 293.37 233.045 0)
      (effects (font (size 1.27 1.27)) hide)
    )
    (property "Author" "Antmicro" (id 6) (at 330.2 239.395 0)
      (effects (font (size 1.27 1.27) (thickness 0.15)) (justify left bottom) hide)
    )
    (property "License" "Apache-2.0" (id 7) (at 330.2 241.935 0)
      (effects (font (size 1.27 1.27) (thickness 0.15)) (justify left bottom) hide)
    )
    (pin "1")
    (pin "2")
    (pin "3")
    (pin "4")
    (pin "5")
    (pin "6")
  )

  (symbol (lib_id "sa800u-baseboard-hw:PWR_FLAG") (at 365.76 221.615 0) (unit 1)
    (in_bom yes) (on_board yes) (fields_autoplaced)
    (property "Reference" "#FLG023" (id 0) (at 365.76 219.71 0)
      (effects (font (size 1.27 1.27)) hide)
    )
    (property "Value" "PWR_FLAG" (id 1) (at 365.76 215.9 0))
    (property "Footprint" "" (id 2) (at 365.76 221.615 0)
      (effects (font (size 1.27 1.27)) hide)
    )
    (property "Datasheet" "~" (id 3) (at 365.76 221.615 0)
      (effects (font (size 1.27 1.27)) hide)
    )
    (pin "1")
  )

  (symbol (lib_id "sa800u-baseboard-hw:GND") (at 293.37 237.49 0) (mirror y) (unit 1)
    (in_bom yes) (on_board yes) (fields_autoplaced)
    (property "Reference" "#PWR0224" (id 0) (at 293.37 243.84 0)
      (effects (font (size 1.27 1.27)) hide)
    )
    (property "Value" "GND" (id 1) (at 293.37 242.57 0))
    (property "Footprint" "" (id 2) (at 293.37 237.49 0)
      (effects (font (size 1.27 1.27)) hide)
    )
    (property "Datasheet" "" (id 3) (at 293.37 237.49 0)
      (effects (font (size 1.27 1.27)) hide)
    )
    (property "Author" "Antmicro" (id 4) (at 284.48 245.11 0)
      (effects (font (size 1.27 1.27) (thickness 0.15)) (justify left bottom) hide)
    )
    (property "License" "Apache-2.0" (id 5) (at 284.48 247.65 0)
      (effects (font (size 1.27 1.27) (thickness 0.15)) (justify left bottom) hide)
    )
    (pin "1")
  )

  (symbol (lib_name "L_2u2_6.1A_XEL4030_2") (lib_id "sa800u-baseboard-hw:L_2u2_6.1A_XEL4030") (at 328.168 151.765 0) (unit 1)
    (in_bom yes) (on_board yes) (fields_autoplaced)
    (property "Reference" "L26" (id 0) (at 330.708 146.05 0))
    (property "Value" "L_2u2_6.1A_XEL4030" (id 1) (at 330.708 146.05 0)
      (effects (font (size 1.27 1.27)) hide)
    )
    (property "Footprint" "sa800u-baseboard-hw-footprints:L_Coilcraft_XEL4030" (id 2) (at 348.488 145.415 0)
      (effects (font (size 1.524 1.524)) hide)
    )
    (property "Datasheet" "https://www.coilcraft.com/getmedia/8245f050-f190-4295-8c41-7c03d662ee3d/xel4030.pdf" (id 3) (at 329.565 151.003 0)
      (effects (font (size 1.524 1.524)) hide)
    )
    (property "MPN" "XEL4030-222MEC" (id 4) (at 333.248 139.065 0)
      (effects (font (size 1.27 1.27)) hide)
    )
    (property "Manufacturer" "Coilcraft" (id 5) (at 335.788 136.525 0)
      (effects (font (size 1.27 1.27)) hide)
    )
    (property "Val" "2u2/6.1A" (id 6) (at 330.708 148.59 0))
    (property "MaxCur" "6.1A" (id 7) (at 330.073 140.97 0)
      (effects (font (size 1.27 1.27)) hide)
    )
    (property "Size" "4x4" (id 8) (at 331.343 143.51 0)
      (effects (font (size 1.27 1.27)) hide)
    )
    (property "ISat" "" (id 9) (at 342.138 168.275 0)
      (effects (font (size 1.27 1.27)) (justify left) hide)
    )
    (property "IMax" "" (id 10) (at 342.138 172.085 0)
      (effects (font (size 1.27 1.27) (thickness 0.15)) (justify left bottom) hide)
    )
    (property "Author" "Antmicro" (id 11) (at 342.138 177.165 0)
      (effects (font (size 1.27 1.27) (thickness 0.15)) (justify left bottom) hide)
    )
    (property "License" "Apache-2.0" (id 12) (at 342.138 179.705 0)
      (effects (font (size 1.27 1.27) (thickness 0.15)) (justify left bottom) hide)
    )
    (pin "1")
    (pin "2")
  )

  (symbol (lib_id "sa800u-baseboard-hw:C_22u_0603") (at 375.285 70.485 270) (unit 1)
    (in_bom yes) (on_board yes) (fields_autoplaced)
    (property "Reference" "C142" (id 0) (at 378.206 71.7613 90)
      (effects (font (size 1.524 1.524)) (justify left))
    )
    (property "Value" "C_22u_0603" (id 1) (at 371.475 70.485 0)
      (effects (font (size 1.524 1.524)) hide)
    )
    (property "Footprint" "sa800u-baseboard-hw-footprints:C_0603_1608Metric" (id 2) (at 380.365 75.565 0)
      (effects (font (size 1.524 1.524)) (justify left) hide)
    )
    (property "Datasheet" " " (id 3) (at 375.285 70.485 0)
      (effects (font (size 1.27 1.27)) hide)
    )
    (property "Manufacturer" "Murata" (id 4) (at 385.445 75.565 0)
      (effects (font (size 1.524 1.524)) (justify left) hide)
    )
    (property "MPN" "GRM188R60J226MEA0D" (id 5) (at 382.905 75.565 0)
      (effects (font (size 1.524 1.524)) (justify left) hide)
    )
    (property "Val" "22u" (id 6) (at 378.206 74.9362 90)
      (effects (font (size 1.27 1.27)) (justify left))
    )
    (property "License" "Apache-2.0" (id 7) (at 352.425 90.805 0)
      (effects (font (size 1.27 1.27) (thickness 0.15)) (justify left bottom) hide)
    )
    (property "Author" "Antmicro" (id 8) (at 349.885 90.805 0)
      (effects (font (size 1.27 1.27) (thickness 0.15)) (justify left bottom) hide)
    )
    (property "Voltage" "" (id 9) (at 347.345 90.805 0)
      (effects (font (size 1.27 1.27)) (justify left bottom) hide)
    )
    (property "Dielectric" "" (id 10) (at 344.805 90.805 0)
      (effects (font (size 1.27 1.27)) (justify left bottom) hide)
    )
    (pin "1")
    (pin "2")
  )

  (symbol (lib_id "sa800u-baseboard-hw:C_22u_0603") (at 389.89 70.485 270) (unit 1)
    (in_bom yes) (on_board yes) (fields_autoplaced)
    (property "Reference" "C143" (id 0) (at 392.303 71.7613 90)
      (effects (font (size 1.524 1.524)) (justify left))
    )
    (property "Value" "C_22u_0603" (id 1) (at 386.08 70.485 0)
      (effects (font (size 1.524 1.524)) hide)
    )
    (property "Footprint" "sa800u-baseboard-hw-footprints:C_0603_1608Metric" (id 2) (at 394.97 75.565 0)
      (effects (font (size 1.524 1.524)) (justify left) hide)
    )
    (property "Datasheet" " " (id 3) (at 389.89 70.485 0)
      (effects (font (size 1.27 1.27)) hide)
    )
    (property "Manufacturer" "Murata" (id 4) (at 400.05 75.565 0)
      (effects (font (size 1.524 1.524)) (justify left) hide)
    )
    (property "MPN" "GRM188R60J226MEA0D" (id 5) (at 397.51 75.565 0)
      (effects (font (size 1.524 1.524)) (justify left) hide)
    )
    (property "Val" "22u" (id 6) (at 392.303 74.9362 90)
      (effects (font (size 1.27 1.27)) (justify left))
    )
    (property "License" "Apache-2.0" (id 7) (at 367.03 90.805 0)
      (effects (font (size 1.27 1.27) (thickness 0.15)) (justify left bottom) hide)
    )
    (property "Author" "Antmicro" (id 8) (at 364.49 90.805 0)
      (effects (font (size 1.27 1.27) (thickness 0.15)) (justify left bottom) hide)
    )
    (property "Voltage" "" (id 9) (at 361.95 90.805 0)
      (effects (font (size 1.27 1.27)) (justify left bottom) hide)
    )
    (property "Dielectric" "" (id 10) (at 359.41 90.805 0)
      (effects (font (size 1.27 1.27)) (justify left bottom) hide)
    )
    (pin "1")
    (pin "2")
  )

  (symbol (lib_id "sa800u-baseboard-hw:GND") (at 375.285 75.565 0) (unit 1)
    (in_bom yes) (on_board yes) (fields_autoplaced)
    (property "Reference" "#PWR0237" (id 0) (at 375.285 81.915 0)
      (effects (font (size 1.27 1.27)) hide)
    )
    (property "Value" "GND" (id 1) (at 375.285 80.01 0))
    (property "Footprint" "" (id 2) (at 375.285 75.565 0)
      (effects (font (size 1.27 1.27)) hide)
    )
    (property "Datasheet" "" (id 3) (at 375.285 75.565 0)
      (effects (font (size 1.27 1.27)) hide)
    )
    (property "Author" "Antmicro" (id 4) (at 384.175 83.185 0)
      (effects (font (size 1.27 1.27) (thickness 0.15)) (justify left bottom) hide)
    )
    (property "License" "Apache-2.0" (id 5) (at 384.175 85.725 0)
      (effects (font (size 1.27 1.27) (thickness 0.15)) (justify left bottom) hide)
    )
    (pin "1")
  )

  (symbol (lib_id "sa800u-baseboard-hw:GND") (at 389.89 75.565 0) (unit 1)
    (in_bom yes) (on_board yes) (fields_autoplaced)
    (property "Reference" "#PWR0238" (id 0) (at 389.89 81.915 0)
      (effects (font (size 1.27 1.27)) hide)
    )
    (property "Value" "GND" (id 1) (at 389.89 80.01 0))
    (property "Footprint" "" (id 2) (at 389.89 75.565 0)
      (effects (font (size 1.27 1.27)) hide)
    )
    (property "Datasheet" "" (id 3) (at 389.89 75.565 0)
      (effects (font (size 1.27 1.27)) hide)
    )
    (property "Author" "Antmicro" (id 4) (at 398.78 83.185 0)
      (effects (font (size 1.27 1.27) (thickness 0.15)) (justify left bottom) hide)
    )
    (property "License" "Apache-2.0" (id 5) (at 398.78 85.725 0)
      (effects (font (size 1.27 1.27) (thickness 0.15)) (justify left bottom) hide)
    )
    (pin "1")
  )

  (symbol (lib_id "sa800u-baseboard-hw:GND") (at 361.95 158.115 0) (mirror y) (unit 1)
    (in_bom yes) (on_board yes) (fields_autoplaced)
    (property "Reference" "#PWR0235" (id 0) (at 361.95 164.465 0)
      (effects (font (size 1.27 1.27)) hide)
    )
    (property "Value" "GND" (id 1) (at 361.95 162.56 0))
    (property "Footprint" "" (id 2) (at 361.95 158.115 0)
      (effects (font (size 1.27 1.27)) hide)
    )
    (property "Datasheet" "" (id 3) (at 361.95 158.115 0)
      (effects (font (size 1.27 1.27)) hide)
    )
    (property "Author" "Antmicro" (id 4) (at 353.06 165.735 0)
      (effects (font (size 1.27 1.27) (thickness 0.15)) (justify left bottom) hide)
    )
    (property "License" "Apache-2.0" (id 5) (at 353.06 168.275 0)
      (effects (font (size 1.27 1.27) (thickness 0.15)) (justify left bottom) hide)
    )
    (pin "1")
  )

  (symbol (lib_id "sa800u-baseboard-hw:PWR_FLAG") (at 365.76 186.69 0) (unit 1)
    (in_bom yes) (on_board yes) (fields_autoplaced)
    (property "Reference" "#FLG022" (id 0) (at 365.76 184.785 0)
      (effects (font (size 1.27 1.27)) hide)
    )
    (property "Value" "PWR_FLAG" (id 1) (at 365.76 181.61 0))
    (property "Footprint" "" (id 2) (at 365.76 186.69 0)
      (effects (font (size 1.27 1.27)) hide)
    )
    (property "Datasheet" "~" (id 3) (at 365.76 186.69 0)
      (effects (font (size 1.27 1.27)) hide)
    )
    (pin "1")
  )

  (symbol (lib_id "sa800u-baseboard-hw:C_100n_0402") (at 316.23 191.77 0) (unit 1)
    (in_bom yes) (on_board yes)
    (property "Reference" "C133" (id 0) (at 322.453 190.627 0)
      (effects (font (size 1.524 1.524)))
    )
    (property "Value" "C_100n_0402" (id 1) (at 316.23 195.58 0)
      (effects (font (size 1.524 1.524)) hide)
    )
    (property "Footprint" "sa800u-baseboard-hw-footprints:C_0402_1005Metric" (id 2) (at 321.31 186.69 0)
      (effects (font (size 1.524 1.524)) (justify left) hide)
    )
    (property "Datasheet" "https://search.murata.co.jp/Ceramy/image/img/A01X/G101/ENG/GRM155R61H104KE14-01.pdf" (id 3) (at 316.23 191.77 0)
      (effects (font (size 1.27 1.27)) hide)
    )
    (property "Manufacturer" "Murata" (id 4) (at 321.31 181.61 0)
      (effects (font (size 1.524 1.524)) (justify left) hide)
    )
    (property "MPN" "GRM155R61H104KE14D" (id 5) (at 321.31 184.15 0)
      (effects (font (size 1.524 1.524)) (justify left) hide)
    )
    (property "Val" "100n" (id 6) (at 321.945 192.913 0))
    (property "License" "Apache-2.0" (id 7) (at 336.55 214.63 0)
      (effects (font (size 1.27 1.27) (thickness 0.15)) (justify left bottom) hide)
    )
    (property "Author" "Antmicro" (id 8) (at 336.55 217.17 0)
      (effects (font (size 1.27 1.27) (thickness 0.15)) (justify left bottom) hide)
    )
    (property "Voltage" "50V" (id 9) (at 336.55 219.71 0)
      (effects (font (size 1.27 1.27)) (justify left bottom) hide)
    )
    (property "Dielectric" "X5R" (id 10) (at 336.55 222.25 0)
      (effects (font (size 1.27 1.27)) (justify left bottom) hide)
    )
    (pin "1")
    (pin "2")
  )

  (symbol (lib_id "sa800u-baseboard-hw:C_22u_0603") (at 347.345 187.96 270) (unit 1)
    (in_bom yes) (on_board yes) (fields_autoplaced)
    (property "Reference" "C136" (id 0) (at 350.647 189.2363 90)
      (effects (font (size 1.524 1.524)) (justify left))
    )
    (property "Value" "C_22u_0603" (id 1) (at 343.535 187.96 0)
      (effects (font (size 1.524 1.524)) hide)
    )
    (property "Footprint" "sa800u-baseboard-hw-footprints:C_0603_1608Metric" (id 2) (at 352.425 193.04 0)
      (effects (font (size 1.524 1.524)) (justify left) hide)
    )
    (property "Datasheet" " " (id 3) (at 347.345 187.96 0)
      (effects (font (size 1.27 1.27)) hide)
    )
    (property "Manufacturer" "Murata" (id 4) (at 357.505 193.04 0)
      (effects (font (size 1.524 1.524)) (justify left) hide)
    )
    (property "MPN" "GRM188R60J226MEA0D" (id 5) (at 354.965 193.04 0)
      (effects (font (size 1.524 1.524)) (justify left) hide)
    )
    (property "Val" "22u" (id 6) (at 350.647 192.4112 90)
      (effects (font (size 1.27 1.27)) (justify left))
    )
    (property "License" "Apache-2.0" (id 7) (at 324.485 208.28 0)
      (effects (font (size 1.27 1.27) (thickness 0.15)) (justify left bottom) hide)
    )
    (property "Author" "Antmicro" (id 8) (at 321.945 208.28 0)
      (effects (font (size 1.27 1.27) (thickness 0.15)) (justify left bottom) hide)
    )
    (property "Voltage" "" (id 9) (at 319.405 208.28 0)
      (effects (font (size 1.27 1.27)) (justify left bottom) hide)
    )
    (property "Dielectric" "" (id 10) (at 316.865 208.28 0)
      (effects (font (size 1.27 1.27)) (justify left bottom) hide)
    )
    (pin "1")
    (pin "2")
  )

  (symbol (lib_id "sa800u-baseboard-hw:C_22u_0603") (at 361.315 187.96 270) (unit 1)
    (in_bom yes) (on_board yes) (fields_autoplaced)
    (property "Reference" "C139" (id 0) (at 364.49 189.2363 90)
      (effects (font (size 1.524 1.524)) (justify left))
    )
    (property "Value" "C_22u_0603" (id 1) (at 357.505 187.96 0)
      (effects (font (size 1.524 1.524)) hide)
    )
    (property "Footprint" "sa800u-baseboard-hw-footprints:C_0603_1608Metric" (id 2) (at 366.395 193.04 0)
      (effects (font (size 1.524 1.524)) (justify left) hide)
    )
    (property "Datasheet" " " (id 3) (at 361.315 187.96 0)
      (effects (font (size 1.27 1.27)) hide)
    )
    (property "Manufacturer" "Murata" (id 4) (at 371.475 193.04 0)
      (effects (font (size 1.524 1.524)) (justify left) hide)
    )
    (property "MPN" "GRM188R60J226MEA0D" (id 5) (at 368.935 193.04 0)
      (effects (font (size 1.524 1.524)) (justify left) hide)
    )
    (property "Val" "22u" (id 6) (at 364.49 192.4112 90)
      (effects (font (size 1.27 1.27)) (justify left))
    )
    (property "License" "Apache-2.0" (id 7) (at 338.455 208.28 0)
      (effects (font (size 1.27 1.27) (thickness 0.15)) (justify left bottom) hide)
    )
    (property "Author" "Antmicro" (id 8) (at 335.915 208.28 0)
      (effects (font (size 1.27 1.27) (thickness 0.15)) (justify left bottom) hide)
    )
    (property "Voltage" "" (id 9) (at 333.375 208.28 0)
      (effects (font (size 1.27 1.27)) (justify left bottom) hide)
    )
    (property "Dielectric" "" (id 10) (at 330.835 208.28 0)
      (effects (font (size 1.27 1.27)) (justify left bottom) hide)
    )
    (pin "1")
    (pin "2")
  )

  (symbol (lib_id "sa800u-baseboard-hw:C_100n_0402") (at 316.23 226.695 0) (unit 1)
    (in_bom yes) (on_board yes)
    (property "Reference" "C134" (id 0) (at 322.453 225.425 0)
      (effects (font (size 1.524 1.524)))
    )
    (property "Value" "C_100n_0402" (id 1) (at 316.23 230.505 0)
      (effects (font (size 1.524 1.524)) hide)
    )
    (property "Footprint" "sa800u-baseboard-hw-footprints:C_0402_1005Metric" (id 2) (at 321.31 221.615 0)
      (effects (font (size 1.524 1.524)) (justify left) hide)
    )
    (property "Datasheet" "https://search.murata.co.jp/Ceramy/image/img/A01X/G101/ENG/GRM155R61H104KE14-01.pdf" (id 3) (at 316.23 226.695 0)
      (effects (font (size 1.27 1.27)) hide)
    )
    (property "Manufacturer" "Murata" (id 4) (at 321.31 216.535 0)
      (effects (font (size 1.524 1.524)) (justify left) hide)
    )
    (property "MPN" "GRM155R61H104KE14D" (id 5) (at 321.31 219.075 0)
      (effects (font (size 1.524 1.524)) (justify left) hide)
    )
    (property "Val" "100n" (id 6) (at 322.453 227.965 0))
    (property "License" "Apache-2.0" (id 7) (at 336.55 249.555 0)
      (effects (font (size 1.27 1.27) (thickness 0.15)) (justify left bottom) hide)
    )
    (property "Author" "Antmicro" (id 8) (at 336.55 252.095 0)
      (effects (font (size 1.27 1.27) (thickness 0.15)) (justify left bottom) hide)
    )
    (property "Voltage" "50V" (id 9) (at 336.55 254.635 0)
      (effects (font (size 1.27 1.27)) (justify left bottom) hide)
    )
    (property "Dielectric" "X5R" (id 10) (at 336.55 257.175 0)
      (effects (font (size 1.27 1.27)) (justify left bottom) hide)
    )
    (pin "1")
    (pin "2")
  )

  (symbol (lib_id "sa800u-baseboard-hw:R_10k_0402") (at 336.55 223.52 270) (unit 1)
    (in_bom yes) (on_board yes) (fields_autoplaced)
    (property "Reference" "R139" (id 0) (at 339.09 224.79 90)
      (effects (font (size 1.524 1.524)) (justify left))
    )
    (property "Value" "R_10k_0402" (id 1) (at 332.74 223.52 0)
      (effects (font (size 1.524 1.524)) hide)
    )
    (property "Footprint" "sa800u-baseboard-hw-footprints:R_0402_1005Metric" (id 2) (at 341.63 228.6 0)
      (effects (font (size 1.524 1.524)) (justify left) hide)
    )
    (property "Datasheet" "https://www.bourns.com/docs/product-datasheets/cr.pdf" (id 3) (at 336.55 223.52 0)
      (effects (font (size 1.27 1.27)) hide)
    )
    (property "Manufacturer" "Bourns" (id 4) (at 346.71 228.6 0)
      (effects (font (size 1.524 1.524)) (justify left) hide)
    )
    (property "MPN" "CR0402-FX-1002GLF" (id 5) (at 344.17 228.6 0)
      (effects (font (size 1.524 1.524)) (justify left) hide)
    )
    (property "Val" "10k" (id 6) (at 339.09 227.9649 90)
      (effects (font (size 1.27 1.27)) (justify left))
    )
    (property "License" "Apache-2.0" (id 7) (at 311.15 243.84 0)
      (effects (font (size 1.27 1.27) (thickness 0.15)) (justify left bottom) hide)
    )
    (property "Author" "Antmicro" (id 8) (at 308.61 243.84 0)
      (effects (font (size 1.27 1.27) (thickness 0.15)) (justify left bottom) hide)
    )
    (property "Tolerance" "1%" (id 9) (at 326.39 243.84 0)
      (effects (font (size 1.27 1.27)) (justify left bottom) hide)
    )
    (pin "1")
    (pin "2")
  )

  (symbol (lib_id "sa800u-baseboard-hw:C_22u_0603") (at 347.345 222.885 270) (unit 1)
    (in_bom yes) (on_board yes) (fields_autoplaced)
    (property "Reference" "C137" (id 0) (at 350.139 224.1613 90)
      (effects (font (size 1.524 1.524)) (justify left))
    )
    (property "Value" "C_22u_0603" (id 1) (at 343.535 222.885 0)
      (effects (font (size 1.524 1.524)) hide)
    )
    (property "Footprint" "sa800u-baseboard-hw-footprints:C_0603_1608Metric" (id 2) (at 352.425 227.965 0)
      (effects (font (size 1.524 1.524)) (justify left) hide)
    )
    (property "Datasheet" " " (id 3) (at 347.345 222.885 0)
      (effects (font (size 1.27 1.27)) hide)
    )
    (property "Manufacturer" "Murata" (id 4) (at 357.505 227.965 0)
      (effects (font (size 1.524 1.524)) (justify left) hide)
    )
    (property "MPN" "GRM188R60J226MEA0D" (id 5) (at 354.965 227.965 0)
      (effects (font (size 1.524 1.524)) (justify left) hide)
    )
    (property "Val" "22u" (id 6) (at 350.139 227.3362 90)
      (effects (font (size 1.27 1.27)) (justify left))
    )
    (property "License" "Apache-2.0" (id 7) (at 324.485 243.205 0)
      (effects (font (size 1.27 1.27) (thickness 0.15)) (justify left bottom) hide)
    )
    (property "Author" "Antmicro" (id 8) (at 321.945 243.205 0)
      (effects (font (size 1.27 1.27) (thickness 0.15)) (justify left bottom) hide)
    )
    (property "Voltage" "" (id 9) (at 319.405 243.205 0)
      (effects (font (size 1.27 1.27)) (justify left bottom) hide)
    )
    (property "Dielectric" "" (id 10) (at 316.865 243.205 0)
      (effects (font (size 1.27 1.27)) (justify left bottom) hide)
    )
    (pin "1")
    (pin "2")
  )

  (symbol (lib_id "sa800u-baseboard-hw:GND") (at 347.345 227.965 0) (mirror y) (unit 1)
    (in_bom yes) (on_board yes) (fields_autoplaced)
    (property "Reference" "#PWR0232" (id 0) (at 347.345 234.315 0)
      (effects (font (size 1.27 1.27)) hide)
    )
    (property "Value" "GND" (id 1) (at 347.345 232.41 0))
    (property "Footprint" "" (id 2) (at 347.345 227.965 0)
      (effects (font (size 1.27 1.27)) hide)
    )
    (property "Datasheet" "" (id 3) (at 347.345 227.965 0)
      (effects (font (size 1.27 1.27)) hide)
    )
    (property "Author" "Antmicro" (id 4) (at 338.455 235.585 0)
      (effects (font (size 1.27 1.27) (thickness 0.15)) (justify left bottom) hide)
    )
    (property "License" "Apache-2.0" (id 5) (at 338.455 238.125 0)
      (effects (font (size 1.27 1.27) (thickness 0.15)) (justify left bottom) hide)
    )
    (pin "1")
  )

  (symbol (lib_id "sa800u-baseboard-hw:PWR_FLAG") (at 394.335 41.91 0) (unit 1)
    (in_bom yes) (on_board yes) (fields_autoplaced)
    (property "Reference" "#FLG025" (id 0) (at 394.335 40.005 0)
      (effects (font (size 1.27 1.27)) hide)
    )
    (property "Value" "PWR_FLAG" (id 1) (at 394.335 36.83 0))
    (property "Footprint" "" (id 2) (at 394.335 41.91 0)
      (effects (font (size 1.27 1.27)) hide)
    )
    (property "Datasheet" "~" (id 3) (at 394.335 41.91 0)
      (effects (font (size 1.27 1.27)) hide)
    )
    (pin "1")
  )

  (symbol (lib_id "sa800u-baseboard-hw:PWR_FLAG") (at 394.335 69.215 0) (unit 1)
    (in_bom yes) (on_board yes) (fields_autoplaced)
    (property "Reference" "#FLG026" (id 0) (at 394.335 67.31 0)
      (effects (font (size 1.27 1.27)) hide)
    )
    (property "Value" "PWR_FLAG" (id 1) (at 394.335 63.5 0))
    (property "Footprint" "" (id 2) (at 394.335 69.215 0)
      (effects (font (size 1.27 1.27)) hide)
    )
    (property "Datasheet" "~" (id 3) (at 394.335 69.215 0)
      (effects (font (size 1.27 1.27)) hide)
    )
    (pin "1")
  )

  (symbol (lib_id "sa800u-baseboard-hw:PWR_FLAG") (at 185.928 54.61 0) (unit 1)
    (in_bom yes) (on_board yes) (fields_autoplaced)
    (property "Reference" "#FLG021" (id 0) (at 185.928 52.705 0)
      (effects (font (size 1.27 1.27)) hide)
    )
    (property "Value" "PWR_FLAG" (id 1) (at 185.928 49.53 0))
    (property "Footprint" "" (id 2) (at 185.928 54.61 0)
      (effects (font (size 1.27 1.27)) hide)
    )
    (property "Datasheet" "~" (id 3) (at 185.928 54.61 0)
      (effects (font (size 1.27 1.27)) hide)
    )
    (pin "1")
  )

  (symbol (lib_id "sa800u-baseboard-hw:GND") (at 33.782 59.055 0) (unit 1)
    (in_bom yes) (on_board yes) (fields_autoplaced)
    (property "Reference" "#PWR0199" (id 0) (at 33.782 65.405 0)
      (effects (font (size 1.27 1.27)) hide)
    )
    (property "Value" "GND" (id 1) (at 33.782 63.5 0))
    (property "Footprint" "" (id 2) (at 33.782 59.055 0)
      (effects (font (size 1.27 1.27)) hide)
    )
    (property "Datasheet" "" (id 3) (at 33.782 59.055 0)
      (effects (font (size 1.27 1.27)) hide)
    )
    (property "Author" "Antmicro" (id 4) (at 42.672 66.675 0)
      (effects (font (size 1.27 1.27) (thickness 0.15)) (justify left bottom) hide)
    )
    (property "License" "Apache-2.0" (id 5) (at 42.672 69.215 0)
      (effects (font (size 1.27 1.27) (thickness 0.15)) (justify left bottom) hide)
    )
    (pin "1")
  )

  (symbol (lib_name "L_2u2_6.1A_XEL4030_1") (lib_id "sa800u-baseboard-hw:L_2u2_6.1A_XEL4030") (at 355.092 69.215 0) (unit 1)
    (in_bom yes) (on_board yes) (fields_autoplaced)
    (property "Reference" "L29" (id 0) (at 357.632 63.5 0))
    (property "Value" "L_2u2_6.1A_XEL4030" (id 1) (at 357.632 63.5 0)
      (effects (font (size 1.27 1.27)) hide)
    )
    (property "Footprint" "sa800u-baseboard-hw-footprints:L_Coilcraft_XEL4030" (id 2) (at 375.412 62.865 0)
      (effects (font (size 1.524 1.524)) hide)
    )
    (property "Datasheet" "https://www.coilcraft.com/getmedia/8245f050-f190-4295-8c41-7c03d662ee3d/xel4030.pdf" (id 3) (at 356.489 68.453 0)
      (effects (font (size 1.524 1.524)) hide)
    )
    (property "MPN" "XEL4030-222MEC" (id 4) (at 360.172 56.515 0)
      (effects (font (size 1.27 1.27)) hide)
    )
    (property "Manufacturer" "Coilcraft" (id 5) (at 362.712 53.975 0)
      (effects (font (size 1.27 1.27)) hide)
    )
    (property "Val" "2u2/6.1A" (id 6) (at 357.632 66.04 0))
    (property "MaxCur" "6.1A" (id 7) (at 356.997 58.42 0)
      (effects (font (size 1.27 1.27)) hide)
    )
    (property "Size" "4x4" (id 8) (at 358.267 60.96 0)
      (effects (font (size 1.27 1.27)) hide)
    )
    (property "ISat" "" (id 9) (at 369.062 85.725 0)
      (effects (font (size 1.27 1.27)) (justify left) hide)
    )
    (property "IMax" "" (id 10) (at 369.062 89.535 0)
      (effects (font (size 1.27 1.27) (thickness 0.15)) (justify left bottom) hide)
    )
    (property "Author" "Antmicro" (id 11) (at 369.062 94.615 0)
      (effects (font (size 1.27 1.27) (thickness 0.15)) (justify left bottom) hide)
    )
    (property "License" "Apache-2.0" (id 12) (at 369.062 97.155 0)
      (effects (font (size 1.27 1.27) (thickness 0.15)) (justify left bottom) hide)
    )
    (pin "1")
    (pin "2")
  )

  (symbol (lib_id "sa800u-baseboard-hw:LTC4417_QFN") (at 80.645 142.24 0) (unit 1)
    (in_bom yes) (on_board yes) (fields_autoplaced)
    (property "Reference" "U17" (id 0) (at 93.345 134.62 0))
    (property "Value" "LTC4417_QFN" (id 1) (at 118.745 154.94 0)
      (effects (font (size 1.27 1.27) (thickness 0.15)) (justify left bottom) hide)
    )
    (property "Footprint" "sa800u-baseboard-hw-footprints:QFN-24-1EP_4x4mm_EP2.1x2.1mm" (id 2) (at 118.745 157.48 0)
      (effects (font (size 1.27 1.27) (thickness 0.15)) (justify left bottom) hide)
    )
    (property "Datasheet" "https://www.mouser.pl/datasheet/2/609/4417f-1271526.pdf" (id 3) (at 118.745 160.02 0)
      (effects (font (size 1.27 1.27) (thickness 0.15)) (justify left bottom) hide)
    )
    (property "MPN" "LTC4417IUF#TRPBF" (id 4) (at 93.345 137.16 0)
      (effects (font (size 1.27 1.27) (thickness 0.15)))
    )
    (property "Manufacturer" "Analog Devices" (id 5) (at 118.745 162.56 0)
      (effects (font (size 1.27 1.27) (thickness 0.15)) (justify left bottom) hide)
    )
    (property "Author" "Antmicro" (id 6) (at 118.745 165.1 0)
      (effects (font (size 1.27 1.27) (thickness 0.15)) (justify left bottom) hide)
    )
    (property "License" "Apache-2.0" (id 7) (at 118.745 167.64 0)
      (effects (font (size 1.27 1.27) (thickness 0.15)) (justify left bottom) hide)
    )
    (pin "1")
    (pin "10")
    (pin "11")
    (pin "12")
    (pin "13")
    (pin "14")
    (pin "15")
    (pin "16")
    (pin "17")
    (pin "18")
    (pin "19")
    (pin "2")
    (pin "20")
    (pin "21")
    (pin "22")
    (pin "23")
    (pin "24")
    (pin "25")
    (pin "3")
    (pin "4")
    (pin "5")
    (pin "6")
    (pin "7")
    (pin "8")
    (pin "9")
  )

  (symbol (lib_name "Si7223DN_2") (lib_id "sa800u-baseboard-hw:Si7223DN") (at 109.855 72.39 270) (mirror x) (unit 1)
    (in_bom yes) (on_board yes) (fields_autoplaced)
    (property "Reference" "Q9" (id 0) (at 118.11 64.1349 90)
      (effects (font (size 1.27 1.27)) (justify left))
    )
    (property "Value" "Si7223DN" (id 1) (at 118.11 66.6749 90)
      (effects (font (size 1.27 1.27)) (justify left))
    )
    (property "Footprint" "sa800u-baseboard-hw-footprints:PowerPak-1212" (id 2) (at 108.585 95.25 0)
      (effects (font (size 1.27 1.27)) hide)
    )
    (property "Datasheet" "https://www.farnell.com/datasheets/2606257.pdf" (id 3) (at 108.585 72.39 0)
      (effects (font (size 1.27 1.27)) hide)
    )
    (property "MPN" "SI7223DN-T1-GE3" (id 4) (at 109.855 90.17 0)
      (effects (font (size 1.27 1.27)) hide)
    )
    (property "Manufacturer" "Vishay" (id 5) (at 111.125 87.63 0)
      (effects (font (size 1.27 1.27)) hide)
    )
    (property "Author" "Antmicro" (id 6) (at 99.695 49.53 0)
      (effects (font (size 1.27 1.27) (thickness 0.15)) (justify left bottom) hide)
    )
    (property "License" "Apache-2.0" (id 7) (at 97.155 49.53 0)
      (effects (font (size 1.27 1.27) (thickness 0.15)) (justify left bottom) hide)
    )
    (pin "1")
    (pin "2")
    (pin "3")
    (pin "4")
    (pin "5")
    (pin "6")
    (pin "7")
    (pin "8")
  )

  (symbol (lib_id "sa800u-baseboard-hw:Si7223DN") (at 122.555 92.71 270) (mirror x) (unit 1)
    (in_bom yes) (on_board yes) (fields_autoplaced)
    (property "Reference" "Q11" (id 0) (at 130.81 84.4549 90)
      (effects (font (size 1.27 1.27)) (justify left))
    )
    (property "Value" "Si7223DN" (id 1) (at 130.81 86.9949 90)
      (effects (font (size 1.27 1.27)) (justify left))
    )
    (property "Footprint" "sa800u-baseboard-hw-footprints:PowerPak-1212" (id 2) (at 121.285 115.57 0)
      (effects (font (size 1.27 1.27)) hide)
    )
    (property "Datasheet" "https://www.farnell.com/datasheets/2606257.pdf" (id 3) (at 121.285 92.71 0)
      (effects (font (size 1.27 1.27)) hide)
    )
    (property "MPN" "SI7223DN-T1-GE3" (id 4) (at 122.555 110.49 0)
      (effects (font (size 1.27 1.27)) hide)
    )
    (property "Manufacturer" "Vishay" (id 5) (at 123.825 107.95 0)
      (effects (font (size 1.27 1.27)) hide)
    )
    (property "Author" "Antmicro" (id 6) (at 112.395 69.85 0)
      (effects (font (size 1.27 1.27) (thickness 0.15)) (justify left bottom) hide)
    )
    (property "License" "Apache-2.0" (id 7) (at 109.855 69.85 0)
      (effects (font (size 1.27 1.27) (thickness 0.15)) (justify left bottom) hide)
    )
    (pin "1")
    (pin "2")
    (pin "3")
    (pin "4")
    (pin "5")
    (pin "6")
    (pin "7")
    (pin "8")
  )

  (symbol (lib_name "Si7223DN_1") (lib_id "sa800u-baseboard-hw:Si7223DN") (at 135.255 114.3 270) (mirror x) (unit 1)
    (in_bom yes) (on_board yes) (fields_autoplaced)
    (property "Reference" "Q12" (id 0) (at 143.51 106.0449 90)
      (effects (font (size 1.27 1.27)) (justify left))
    )
    (property "Value" "Si7223DN" (id 1) (at 143.51 108.5849 90)
      (effects (font (size 1.27 1.27)) (justify left))
    )
    (property "Footprint" "sa800u-baseboard-hw-footprints:PowerPak-1212" (id 2) (at 133.985 137.16 0)
      (effects (font (size 1.27 1.27)) hide)
    )
    (property "Datasheet" "https://www.farnell.com/datasheets/2606257.pdf" (id 3) (at 133.985 114.3 0)
      (effects (font (size 1.27 1.27)) hide)
    )
    (property "MPN" "SI7223DN-T1-GE3" (id 4) (at 135.255 132.08 0)
      (effects (font (size 1.27 1.27)) hide)
    )
    (property "Manufacturer" "Vishay" (id 5) (at 136.525 129.54 0)
      (effects (font (size 1.27 1.27)) hide)
    )
    (property "Author" "Antmicro" (id 6) (at 125.095 91.44 0)
      (effects (font (size 1.27 1.27) (thickness 0.15)) (justify left bottom) hide)
    )
    (property "License" "Apache-2.0" (id 7) (at 122.555 91.44 0)
      (effects (font (size 1.27 1.27) (thickness 0.15)) (justify left bottom) hide)
    )
    (pin "1")
    (pin "2")
    (pin "3")
    (pin "4")
    (pin "5")
    (pin "6")
    (pin "7")
    (pin "8")
  )

  (symbol (lib_id "sa800u-baseboard-hw:R_10k_0402") (at 185.928 60.96 90) (unit 1)
    (in_bom yes) (on_board yes) (fields_autoplaced)
    (property "Reference" "R121" (id 0) (at 187.833 57.15 90)
      (effects (font (size 1.524 1.524)) (justify right))
    )
    (property "Value" "R_10k_0402" (id 1) (at 189.738 60.96 0)
      (effects (font (size 1.524 1.524)) hide)
    )
    (property "Footprint" "sa800u-baseboard-hw-footprints:R_0402_1005Metric" (id 2) (at 180.848 55.88 0)
      (effects (font (size 1.524 1.524)) (justify left) hide)
    )
    (property "Datasheet" "https://www.bourns.com/docs/product-datasheets/cr.pdf" (id 3) (at 185.928 60.96 0)
      (effects (font (size 1.27 1.27)) hide)
    )
    (property "Manufacturer" "Bourns" (id 4) (at 175.768 55.88 0)
      (effects (font (size 1.524 1.524)) (justify left) hide)
    )
    (property "MPN" "CR0402-FX-1002GLF" (id 5) (at 178.308 55.88 0)
      (effects (font (size 1.524 1.524)) (justify left) hide)
    )
    (property "Val" "10k" (id 6) (at 187.833 60.3249 90)
      (effects (font (size 1.27 1.27)) (justify right))
    )
    (property "License" "Apache-2.0" (id 7) (at 211.328 40.64 0)
      (effects (font (size 1.27 1.27) (thickness 0.15)) (justify left bottom) hide)
    )
    (property "Author" "Antmicro" (id 8) (at 213.868 40.64 0)
      (effects (font (size 1.27 1.27) (thickness 0.15)) (justify left bottom) hide)
    )
    (property "Tolerance" "1%" (id 9) (at 196.088 40.64 0)
      (effects (font (size 1.27 1.27)) (justify left bottom) hide)
    )
    (pin "1")
    (pin "2")
  )

  (symbol (lib_id "sa800u-baseboard-hw:LED_G_0603_KP-1608ZGC") (at 185.928 66.04 270) (unit 1)
    (in_bom yes) (on_board yes) (fields_autoplaced)
    (property "Reference" "D27" (id 0) (at 189.103 68.58 90)
      (effects (font (size 1.524 1.524)) (justify left))
    )
    (property "Value" "KP-1608EC" (id 1) (at 191.7954 64.77 0)
      (effects (font (size 1.524 1.524)) hide)
    )
    (property "Footprint" "sa800u-baseboard-hw-footprints:LED_0603_1608Metric_G" (id 2) (at 175.768 88.9 0)
      (effects (font (size 1.27 1.27) (thickness 0.15)) (justify left bottom) hide)
    )
    (property "Datasheet" "https://www.farnell.com/datasheets/2045914.pdf" (id 3) (at 173.228 88.9 0)
      (effects (font (size 1.27 1.27) (thickness 0.15)) (justify left bottom) hide)
    )
    (property "MPN" "KP-1608ZGC" (id 4) (at 170.688 88.9 0)
      (effects (font (size 1.27 1.27) (thickness 0.15)) (justify left bottom) hide)
    )
    (property "Manufacturer" "Kingbright" (id 5) (at 168.148 88.9 0)
      (effects (font (size 1.27 1.27) (thickness 0.15)) (justify left bottom) hide)
    )
    (property "Author" "Antmicro" (id 6) (at 165.608 88.9 0)
      (effects (font (size 1.27 1.27) (thickness 0.15)) (justify left bottom) hide)
    )
    (property "License" "Apache-2.0" (id 7) (at 163.068 88.9 0)
      (effects (font (size 1.27 1.27) (thickness 0.15)) (justify left bottom) hide)
    )
    (pin "1")
    (pin "2")
  )

  (symbol (lib_id "sa800u-baseboard-hw:AP62301WU-7") (at 322.58 69.215 0) (unit 1)
    (in_bom yes) (on_board yes) (fields_autoplaced)
    (property "Reference" "U22" (id 0) (at 332.74 60.96 0))
    (property "Value" "AP62301WU-7" (id 1) (at 332.74 63.5 0))
    (property "Footprint" "sa800u-baseboard-hw-footprints:AP62301WU-7-TSOT23-6" (id 2) (at 321.31 85.725 0)
      (effects (font (size 1.27 1.27)) hide)
    )
    (property "Datasheet" "https://www.diodes.com/assets/Datasheets/AP62300_AP62301_AP62300T.pdf" (id 3) (at 321.31 78.105 0)
      (effects (font (size 1.27 1.27)) hide)
    )
    (property "MPN" "AP62301WU-7" (id 4) (at 321.31 83.185 0)
      (effects (font (size 1.27 1.27)) hide)
    )
    (property "Manufacturer" "Diodes Incorporated" (id 5) (at 321.31 80.645 0)
      (effects (font (size 1.27 1.27)) hide)
    )
    (property "Author" "Antmicro" (id 6) (at 358.14 86.995 0)
      (effects (font (size 1.27 1.27) (thickness 0.15)) (justify left bottom) hide)
    )
    (property "License" "Apache-2.0" (id 7) (at 358.14 89.535 0)
      (effects (font (size 1.27 1.27) (thickness 0.15)) (justify left bottom) hide)
    )
    (pin "1")
    (pin "2")
    (pin "3")
    (pin "4")
    (pin "5")
    (pin "6")
  )

  (symbol (lib_id "sa800u-baseboard-hw:GND") (at 255.27 84.455 0) (unit 1)
    (in_bom yes) (on_board yes) (fields_autoplaced)
    (property "Reference" "#PWR0216" (id 0) (at 255.27 90.805 0)
      (effects (font (size 1.27 1.27)) hide)
    )
    (property "Value" "GND" (id 1) (at 255.27 88.9 0))
    (property "Footprint" "" (id 2) (at 255.27 84.455 0)
      (effects (font (size 1.27 1.27)) hide)
    )
    (property "Datasheet" "" (id 3) (at 255.27 84.455 0)
      (effects (font (size 1.27 1.27)) hide)
    )
    (property "Author" "Antmicro" (id 4) (at 264.16 92.075 0)
      (effects (font (size 1.27 1.27) (thickness 0.15)) (justify left bottom) hide)
    )
    (property "License" "Apache-2.0" (id 5) (at 264.16 94.615 0)
      (effects (font (size 1.27 1.27) (thickness 0.15)) (justify left bottom) hide)
    )
    (pin "1")
  )

  (symbol (lib_id "sa800u-baseboard-hw:GND") (at 265.43 84.455 0) (unit 1)
    (in_bom yes) (on_board yes) (fields_autoplaced)
    (property "Reference" "#PWR0217" (id 0) (at 265.43 90.805 0)
      (effects (font (size 1.27 1.27)) hide)
    )
    (property "Value" "GND" (id 1) (at 265.43 88.9 0))
    (property "Footprint" "" (id 2) (at 265.43 84.455 0)
      (effects (font (size 1.27 1.27)) hide)
    )
    (property "Datasheet" "" (id 3) (at 265.43 84.455 0)
      (effects (font (size 1.27 1.27)) hide)
    )
    (property "Author" "Antmicro" (id 4) (at 274.32 92.075 0)
      (effects (font (size 1.27 1.27) (thickness 0.15)) (justify left bottom) hide)
    )
    (property "License" "Apache-2.0" (id 5) (at 274.32 94.615 0)
      (effects (font (size 1.27 1.27) (thickness 0.15)) (justify left bottom) hide)
    )
    (pin "1")
  )

  (symbol (lib_id "sa800u-baseboard-hw:GND") (at 185.928 73.66 0) (unit 1)
    (in_bom yes) (on_board yes) (fields_autoplaced)
    (property "Reference" "#PWR0213" (id 0) (at 185.928 80.01 0)
      (effects (font (size 1.27 1.27)) hide)
    )
    (property "Value" "GND" (id 1) (at 184.023 74.9299 0)
      (effects (font (size 1.27 1.27)) (justify right))
    )
    (property "Footprint" "" (id 2) (at 185.928 73.66 0)
      (effects (font (size 1.27 1.27)) hide)
    )
    (property "Datasheet" "" (id 3) (at 185.928 73.66 0)
      (effects (font (size 1.27 1.27)) hide)
    )
    (property "Author" "Antmicro" (id 4) (at 194.818 81.28 0)
      (effects (font (size 1.27 1.27) (thickness 0.15)) (justify left bottom) hide)
    )
    (property "License" "Apache-2.0" (id 5) (at 194.818 83.82 0)
      (effects (font (size 1.27 1.27) (thickness 0.15)) (justify left bottom) hide)
    )
    (pin "1")
  )

  (symbol (lib_id "sa800u-baseboard-hw:BSS84PH6327XTSA2") (at 277.495 54.61 0) (mirror x) (unit 1)
    (in_bom yes) (on_board yes) (fields_autoplaced)
    (property "Reference" "Q15" (id 0) (at 288.29 55.88 0)
      (effects (font (size 1.524 1.524)) (justify left))
    )
    (property "Value" "BSS84PH6327XTSA2" (id 1) (at 288.29 59.69 0)
      (effects (font (size 1.524 1.524)) (justify left))
    )
    (property "Footprint" "sa800u-baseboard-hw-footprints:SOT-23-3" (id 2) (at 282.575 59.69 0)
      (effects (font (size 1.524 1.524)) (justify left) hide)
    )
    (property "Datasheet" "https://www.mouser.pl/datasheet/2/196/Infineon-BSS84PW-DS-v02_00-EN-1225586.pdf" (id 3) (at 282.575 62.23 0)
      (effects (font (size 1.524 1.524)) (justify left) hide)
    )
    (property "MPN" "BSS84PH6327XTSA2" (id 4) (at 282.575 67.31 0)
      (effects (font (size 1.524 1.524)) (justify left) hide)
    )
    (property "Manufacturer" "Infineon Technologies" (id 5) (at 282.575 82.55 0)
      (effects (font (size 1.524 1.524)) (justify left) hide)
    )
    (property "Author" "Antmicro" (id 6) (at 290.195 36.83 0)
      (effects (font (size 1.27 1.27) (thickness 0.15)) (justify left bottom) hide)
    )
    (property "License" "Apache-2.0" (id 7) (at 290.195 34.29 0)
      (effects (font (size 1.27 1.27) (thickness 0.15)) (justify left bottom) hide)
    )
    (pin "1")
    (pin "2")
    (pin "3")
  )

  (symbol (lib_id "sa800u-baseboard-hw:GND") (at 285.115 86.995 0) (unit 1)
    (in_bom yes) (on_board yes) (fields_autoplaced)
    (property "Reference" "#PWR0221" (id 0) (at 285.115 93.345 0)
      (effects (font (size 1.27 1.27)) hide)
    )
    (property "Value" "GND" (id 1) (at 285.115 91.44 0))
    (property "Footprint" "" (id 2) (at 285.115 86.995 0)
      (effects (font (size 1.27 1.27)) hide)
    )
    (property "Datasheet" "" (id 3) (at 285.115 86.995 0)
      (effects (font (size 1.27 1.27)) hide)
    )
    (property "Author" "Antmicro" (id 4) (at 294.005 94.615 0)
      (effects (font (size 1.27 1.27) (thickness 0.15)) (justify left bottom) hide)
    )
    (property "License" "Apache-2.0" (id 5) (at 294.005 97.155 0)
      (effects (font (size 1.27 1.27) (thickness 0.15)) (justify left bottom) hide)
    )
    (pin "1")
  )

  (symbol (lib_id "sa800u-baseboard-hw:R_10k_0402") (at 312.42 74.295 0) (unit 1)
    (in_bom yes) (on_board yes)
    (property "Reference" "R134" (id 0) (at 320.04 72.771 0)
      (effects (font (size 1.524 1.524)))
    )
    (property "Value" "R_10k_0402" (id 1) (at 312.42 78.105 0)
      (effects (font (size 1.524 1.524)) hide)
    )
    (property "Footprint" "sa800u-baseboard-hw-footprints:R_0402_1005Metric" (id 2) (at 317.5 69.215 0)
      (effects (font (size 1.524 1.524)) (justify left) hide)
    )
    (property "Datasheet" "https://www.bourns.com/docs/product-datasheets/cr.pdf" (id 3) (at 312.42 74.295 0)
      (effects (font (size 1.27 1.27)) hide)
    )
    (property "Manufacturer" "Bourns" (id 4) (at 317.5 64.135 0)
      (effects (font (size 1.524 1.524)) (justify left) hide)
    )
    (property "MPN" "CR0402-FX-1002GLF" (id 5) (at 317.5 66.675 0)
      (effects (font (size 1.524 1.524)) (justify left) hide)
    )
    (property "Val" "10k" (id 6) (at 320.04 75.311 0))
    (property "DNP" "DNP" (id 7) (at 314.96 74.295 0))
    (property "License" "Apache-2.0" (id 8) (at 332.74 99.695 0)
      (effects (font (size 1.27 1.27) (thickness 0.15)) (justify left bottom) hide)
    )
    (property "Author" "Antmicro" (id 9) (at 332.74 102.235 0)
      (effects (font (size 1.27 1.27) (thickness 0.15)) (justify left bottom) hide)
    )
    (property "Tolerance" "1%" (id 10) (at 332.74 84.455 0)
      (effects (font (size 1.27 1.27)) (justify left bottom) hide)
    )
    (pin "1")
    (pin "2")
  )

  (symbol (lib_id "sa800u-baseboard-hw:TP_0.75mm_SMD") (at 289.56 160.782 180) (unit 1)
    (in_bom yes) (on_board yes) (fields_autoplaced)
    (property "Reference" "TP64" (id 0) (at 286.385 164.084 0))
    (property "Value" "TP_0.75mm_SMD" (id 1) (at 289.56 158.242 0)
      (effects (font (size 1.27 1.27)) hide)
    )
    (property "Footprint" "sa800u-baseboard-hw-footprints:TP_SMD_0.75mm" (id 2) (at 284.48 165.862 0)
      (effects (font (size 1.524 1.524)) (justify left) hide)
    )
    (property "Datasheet" "" (id 3) (at 284.48 168.402 0)
      (effects (font (size 1.524 1.524)) (justify left) hide)
    )
    (property "MPN" "" (id 4) (at 271.78 145.542 0)
      (effects (font (size 1.27 1.27) (thickness 0.15)) (justify left bottom) hide)
    )
    (property "Manufacturer" "" (id 5) (at 271.78 143.002 0)
      (effects (font (size 1.27 1.27) (thickness 0.15)) (justify left bottom) hide)
    )
    (property "Author" "Antmicro" (id 6) (at 271.78 140.462 0)
      (effects (font (size 1.27 1.27) (thickness 0.15)) (justify left bottom) hide)
    )
    (property "License" "Apache-2.0" (id 7) (at 271.78 137.922 0)
      (effects (font (size 1.27 1.27) (thickness 0.15)) (justify left bottom) hide)
    )
    (pin "1")
  )

  (symbol (lib_id "sa800u-baseboard-hw:R_1k_0402") (at 269.24 54.61 0) (unit 1)
    (in_bom yes) (on_board yes) (fields_autoplaced)
    (property "Reference" "R126" (id 0) (at 271.78 58.42 0)
      (effects (font (size 1.524 1.524)))
    )
    (property "Value" "R_1k_0402" (id 1) (at 269.24 58.42 0)
      (effects (font (size 1.524 1.524)) hide)
    )
    (property "Footprint" "sa800u-baseboard-hw-footprints:R_0402_1005Metric" (id 2) (at 274.32 49.53 0)
      (effects (font (size 1.524 1.524)) (justify left) hide)
    )
    (property "Datasheet" "https://www.bourns.com/docs/product-datasheets/cr.pdf" (id 3) (at 269.24 54.61 0)
      (effects (font (size 1.27 1.27)) hide)
    )
    (property "Manufacturer" "Bourns" (id 4) (at 274.32 44.45 0)
      (effects (font (size 1.524 1.524)) (justify left) hide)
    )
    (property "MPN" "CR0402-FX-1001GLF" (id 5) (at 274.32 46.99 0)
      (effects (font (size 1.524 1.524)) (justify left) hide)
    )
    (property "Val" "1k" (id 6) (at 271.78 62.23 0))
    (property "License" "Apache-2.0" (id 7) (at 289.56 80.01 0)
      (effects (font (size 1.27 1.27) (thickness 0.15)) (justify left bottom) hide)
    )
    (property "Author" "Antmicro" (id 8) (at 289.56 82.55 0)
      (effects (font (size 1.27 1.27) (thickness 0.15)) (justify left bottom) hide)
    )
    (property "Tolerance" "1%" (id 9) (at 289.56 64.77 0)
      (effects (font (size 1.27 1.27)) (justify left bottom) hide)
    )
    (pin "1")
    (pin "2")
  )

  (symbol (lib_id "sa800u-baseboard-hw:TP_0.75mm_SMD") (at 290.322 191.135 90) (unit 1)
    (in_bom yes) (on_board yes) (fields_autoplaced)
    (property "Reference" "TP65" (id 0) (at 292.1 187.9599 90)
      (effects (font (size 1.27 1.27)) (justify right))
    )
    (property "Value" "TP_0.75mm_SMD" (id 1) (at 292.862 191.135 0)
      (effects (font (size 1.27 1.27)) hide)
    )
    (property "Footprint" "sa800u-baseboard-hw-footprints:TP_SMD_0.75mm" (id 2) (at 285.242 186.055 0)
      (effects (font (size 1.524 1.524)) (justify left) hide)
    )
    (property "Datasheet" "" (id 3) (at 282.702 186.055 0)
      (effects (font (size 1.524 1.524)) (justify left) hide)
    )
    (property "MPN" "" (id 4) (at 305.562 173.355 0)
      (effects (font (size 1.27 1.27) (thickness 0.15)) (justify left bottom) hide)
    )
    (property "Manufacturer" "" (id 5) (at 308.102 173.355 0)
      (effects (font (size 1.27 1.27) (thickness 0.15)) (justify left bottom) hide)
    )
    (property "Author" "Antmicro" (id 6) (at 310.642 173.355 0)
      (effects (font (size 1.27 1.27) (thickness 0.15)) (justify left bottom) hide)
    )
    (property "License" "Apache-2.0" (id 7) (at 313.182 173.355 0)
      (effects (font (size 1.27 1.27) (thickness 0.15)) (justify left bottom) hide)
    )
    (pin "1")
  )

  (symbol (lib_id "sa800u-baseboard-hw:Conn_Molex_NanoFit_1053131202") (at 31.242 54.61 0) (unit 1)
    (in_bom yes) (on_board yes) (fields_autoplaced)
    (property "Reference" "J10" (id 0) (at 24.892 54.6099 0)
      (effects (font (size 1.27 1.27)) (justify right))
    )
    (property "Value" "Conn_Molex_NanoFit_1053131202" (id 1) (at 33.9852 52.7304 0)
      (effects (font (size 1.27 1.27)) hide)
    )
    (property "Footprint" "sa800u-baseboard-hw-footprints:Conn_Molex_NanoFit_1053131202" (id 2) (at 26.797 62.865 0)
      (effects (font (size 1.27 1.27)) hide)
    )
    (property "Datasheet" "https://www.molex.com/molex/products/part-detail/pcb_headers/1053131202" (id 3) (at 31.242 54.61 0)
      (effects (font (size 1.27 1.27)) hide)
    )
    (property "Manufacturer" "Molex" (id 4) (at 29.972 67.945 0)
      (effects (font (size 1.27 1.27)) hide)
    )
    (property "MPN" "1053131202" (id 5) (at 24.892 57.1499 0)
      (effects (font (size 1.27 1.27)) (justify right))
    )
    (property "Author" "Antmicro" (id 6) (at 51.562 74.93 0)
      (effects (font (size 1.27 1.27) (thickness 0.15)) (justify left bottom) hide)
    )
    (property "License" "Apache-2.0" (id 7) (at 51.562 77.47 0)
      (effects (font (size 1.27 1.27) (thickness 0.15)) (justify left bottom) hide)
    )
    (pin "1")
    (pin "2")
  )

  (symbol (lib_id "sa800u-baseboard-hw:TP_0.75mm_SMD") (at 290.068 225.933 90) (unit 1)
    (in_bom yes) (on_board yes) (fields_autoplaced)
    (property "Reference" "TP66" (id 0) (at 292.227 222.7579 90)
      (effects (font (size 1.27 1.27)) (justify right))
    )
    (property "Value" "TP_0.75mm_SMD" (id 1) (at 292.608 225.933 0)
      (effects (font (size 1.27 1.27)) hide)
    )
    (property "Footprint" "sa800u-baseboard-hw-footprints:TP_SMD_0.75mm" (id 2) (at 284.988 220.853 0)
      (effects (font (size 1.524 1.524)) (justify left) hide)
    )
    (property "Datasheet" "" (id 3) (at 282.448 220.853 0)
      (effects (font (size 1.524 1.524)) (justify left) hide)
    )
    (property "MPN" "" (id 4) (at 305.308 208.153 0)
      (effects (font (size 1.27 1.27) (thickness 0.15)) (justify left bottom) hide)
    )
    (property "Manufacturer" "" (id 5) (at 307.848 208.153 0)
      (effects (font (size 1.27 1.27) (thickness 0.15)) (justify left bottom) hide)
    )
    (property "Author" "Antmicro" (id 6) (at 310.388 208.153 0)
      (effects (font (size 1.27 1.27) (thickness 0.15)) (justify left bottom) hide)
    )
    (property "License" "Apache-2.0" (id 7) (at 312.928 208.153 0)
      (effects (font (size 1.27 1.27) (thickness 0.15)) (justify left bottom) hide)
    )
    (pin "1")
  )

  (symbol (lib_id "sa800u-baseboard-hw:R_25k5_0402") (at 285.115 67.818 270) (unit 1)
    (in_bom yes) (on_board yes) (fields_autoplaced)
    (property "Reference" "R129" (id 0) (at 287.02 69.088 90)
      (effects (font (size 1.524 1.524)) (justify left))
    )
    (property "Value" "R_25k5_0402" (id 1) (at 281.305 67.818 0)
      (effects (font (size 1.524 1.524)) hide)
    )
    (property "Footprint" "sa800u-baseboard-hw-footprints:R_0402_1005Metric" (id 2) (at 290.195 72.898 0)
      (effects (font (size 1.524 1.524)) (justify left) hide)
    )
    (property "Datasheet" "https://www.bourns.com/docs/product-datasheets/cr.pdf" (id 3) (at 285.115 67.818 0)
      (effects (font (size 1.27 1.27)) hide)
    )
    (property "Manufacturer" "Bourns" (id 4) (at 295.275 72.898 0)
      (effects (font (size 1.524 1.524)) (justify left) hide)
    )
    (property "MPN" "CR0402-FX-2552GLF" (id 5) (at 292.735 72.898 0)
      (effects (font (size 1.524 1.524)) (justify left) hide)
    )
    (property "Val" "25k5" (id 6) (at 287.02 72.2629 90)
      (effects (font (size 1.27 1.27)) (justify left))
    )
    (property "License" "Apache-2.0" (id 7) (at 259.715 88.138 0)
      (effects (font (size 1.27 1.27) (thickness 0.15)) (justify left bottom) hide)
    )
    (property "Author" "Antmicro" (id 8) (at 257.175 88.138 0)
      (effects (font (size 1.27 1.27) (thickness 0.15)) (justify left bottom) hide)
    )
    (property "Tolerance" "1%" (id 9) (at 274.955 88.138 0)
      (effects (font (size 1.27 1.27)) (justify left bottom) hide)
    )
    (pin "1")
    (pin "2")
  )

  (symbol (lib_id "sa800u-baseboard-hw:R_10k_0402") (at 285.115 78.613 270) (unit 1)
    (in_bom yes) (on_board yes) (fields_autoplaced)
    (property "Reference" "R130" (id 0) (at 287.02 79.883 90)
      (effects (font (size 1.524 1.524)) (justify left))
    )
    (property "Value" "R_10k_0402" (id 1) (at 281.305 78.613 0)
      (effects (font (size 1.524 1.524)) hide)
    )
    (property "Footprint" "sa800u-baseboard-hw-footprints:R_0402_1005Metric" (id 2) (at 290.195 83.693 0)
      (effects (font (size 1.524 1.524)) (justify left) hide)
    )
    (property "Datasheet" "https://www.bourns.com/docs/product-datasheets/cr.pdf" (id 3) (at 285.115 78.613 0)
      (effects (font (size 1.27 1.27)) hide)
    )
    (property "Manufacturer" "Bourns" (id 4) (at 295.275 83.693 0)
      (effects (font (size 1.524 1.524)) (justify left) hide)
    )
    (property "MPN" "CR0402-FX-1002GLF" (id 5) (at 292.735 83.693 0)
      (effects (font (size 1.524 1.524)) (justify left) hide)
    )
    (property "Val" "10k" (id 6) (at 287.02 83.0579 90)
      (effects (font (size 1.27 1.27)) (justify left))
    )
    (property "License" "Apache-2.0" (id 7) (at 259.715 98.933 0)
      (effects (font (size 1.27 1.27) (thickness 0.15)) (justify left bottom) hide)
    )
    (property "Author" "Antmicro" (id 8) (at 257.175 98.933 0)
      (effects (font (size 1.27 1.27) (thickness 0.15)) (justify left bottom) hide)
    )
    (property "Tolerance" "1%" (id 9) (at 274.955 98.933 0)
      (effects (font (size 1.27 1.27)) (justify left bottom) hide)
    )
    (pin "1")
    (pin "2")
  )

  (symbol (lib_id "sa800u-baseboard-hw:TP_0.75mm_SMD") (at 302.26 52.959 90) (unit 1)
    (in_bom yes) (on_board yes) (fields_autoplaced)
    (property "Reference" "TP67" (id 0) (at 302.26 45.847 90))
    (property "Value" "TP_0.75mm_SMD" (id 1) (at 304.8 52.959 0)
      (effects (font (size 1.27 1.27)) hide)
    )
    (property "Footprint" "sa800u-baseboard-hw-footprints:TP_SMD_0.75mm" (id 2) (at 297.18 47.879 0)
      (effects (font (size 1.524 1.524)) (justify left) hide)
    )
    (property "Datasheet" "" (id 3) (at 294.64 47.879 0)
      (effects (font (size 1.524 1.524)) (justify left) hide)
    )
    (property "MPN" "" (id 4) (at 317.5 35.179 0)
      (effects (font (size 1.27 1.27) (thickness 0.15)) (justify left bottom) hide)
    )
    (property "Manufacturer" "" (id 5) (at 320.04 35.179 0)
      (effects (font (size 1.27 1.27) (thickness 0.15)) (justify left bottom) hide)
    )
    (property "Author" "Antmicro" (id 6) (at 322.58 35.179 0)
      (effects (font (size 1.27 1.27) (thickness 0.15)) (justify left bottom) hide)
    )
    (property "License" "Apache-2.0" (id 7) (at 325.12 35.179 0)
      (effects (font (size 1.27 1.27) (thickness 0.15)) (justify left bottom) hide)
    )
    (pin "1")
  )

  (symbol (lib_id "sa800u-baseboard-hw:TP_0.75mm_SMD") (at 315.849 78.486 270) (unit 1)
    (in_bom yes) (on_board yes) (fields_autoplaced)
    (property "Reference" "TP69" (id 0) (at 315.849 84.582 90))
    (property "Value" "TP_0.75mm_SMD" (id 1) (at 313.309 78.486 0)
      (effects (font (size 1.27 1.27)) hide)
    )
    (property "Footprint" "sa800u-baseboard-hw-footprints:TP_SMD_0.75mm" (id 2) (at 320.929 83.566 0)
      (effects (font (size 1.524 1.524)) (justify left) hide)
    )
    (property "Datasheet" "" (id 3) (at 323.469 83.566 0)
      (effects (font (size 1.524 1.524)) (justify left) hide)
    )
    (property "MPN" "" (id 4) (at 300.609 96.266 0)
      (effects (font (size 1.27 1.27) (thickness 0.15)) (justify left bottom) hide)
    )
    (property "Manufacturer" "" (id 5) (at 298.069 96.266 0)
      (effects (font (size 1.27 1.27) (thickness 0.15)) (justify left bottom) hide)
    )
    (property "Author" "Antmicro" (id 6) (at 295.529 96.266 0)
      (effects (font (size 1.27 1.27) (thickness 0.15)) (justify left bottom) hide)
    )
    (property "License" "Apache-2.0" (id 7) (at 292.989 96.266 0)
      (effects (font (size 1.27 1.27) (thickness 0.15)) (justify left bottom) hide)
    )
    (pin "1")
  )

  (symbol (lib_id "sa800u-baseboard-hw:R_10k_0402") (at 286.385 156.845 0) (unit 1)
    (in_bom yes) (on_board yes)
    (property "Reference" "R131" (id 0) (at 288.925 154.686 0)
      (effects (font (size 1.524 1.524)))
    )
    (property "Value" "R_10k_0402" (id 1) (at 286.385 160.655 0)
      (effects (font (size 1.524 1.524)) hide)
    )
    (property "Footprint" "sa800u-baseboard-hw-footprints:R_0402_1005Metric" (id 2) (at 291.465 151.765 0)
      (effects (font (size 1.524 1.524)) (justify left) hide)
    )
    (property "Datasheet" "https://www.bourns.com/docs/product-datasheets/cr.pdf" (id 3) (at 286.385 156.845 0)
      (effects (font (size 1.27 1.27)) hide)
    )
    (property "Manufacturer" "Bourns" (id 4) (at 291.465 146.685 0)
      (effects (font (size 1.524 1.524)) (justify left) hide)
    )
    (property "MPN" "CR0402-FX-1002GLF" (id 5) (at 291.465 149.225 0)
      (effects (font (size 1.524 1.524)) (justify left) hide)
    )
    (property "Val" "10k" (id 6) (at 289.179 158.877 0))
    (property "DNP" "" (id 7) (at 288.8742 155.067 90)
      (effects (font (size 1.27 1.27)) (justify left) hide)
    )
    (property "License" "Apache-2.0" (id 8) (at 306.705 182.245 0)
      (effects (font (size 1.27 1.27) (thickness 0.15)) (justify left bottom) hide)
    )
    (property "Author" "Antmicro" (id 9) (at 306.705 184.785 0)
      (effects (font (size 1.27 1.27) (thickness 0.15)) (justify left bottom) hide)
    )
    (property "Tolerance" "1%" (id 10) (at 306.705 167.005 0)
      (effects (font (size 1.27 1.27)) (justify left bottom) hide)
    )
    (pin "1")
    (pin "2")
  )

  (symbol (lib_id "sa800u-baseboard-hw:GND") (at 106.807 215.9 0) (unit 1)
    (in_bom yes) (on_board yes) (fields_autoplaced)
    (property "Reference" "#PWR0208" (id 0) (at 106.807 222.25 0)
      (effects (font (size 1.27 1.27)) hide)
    )
    (property "Value" "GND" (id 1) (at 106.807 220.98 0))
    (property "Footprint" "" (id 2) (at 106.807 215.9 0)
      (effects (font (size 1.27 1.27)) hide)
    )
    (property "Datasheet" "" (id 3) (at 106.807 215.9 0)
      (effects (font (size 1.27 1.27)) hide)
    )
    (property "Author" "Antmicro" (id 4) (at 115.697 223.52 0)
      (effects (font (size 1.27 1.27) (thickness 0.15)) (justify left bottom) hide)
    )
    (property "License" "Apache-2.0" (id 5) (at 115.697 226.06 0)
      (effects (font (size 1.27 1.27) (thickness 0.15)) (justify left bottom) hide)
    )
    (pin "1")
  )

  (symbol (lib_id "sa800u-baseboard-hw:TP_0.75mm_SMD") (at 254 70.104 180) (unit 1)
    (in_bom yes) (on_board yes) (fields_autoplaced)
    (property "Reference" "TP59" (id 0) (at 250.825 66.548 0))
    (property "Value" "TP_0.75mm_SMD" (id 1) (at 254 67.564 0)
      (effects (font (size 1.27 1.27)) hide)
    )
    (property "Footprint" "sa800u-baseboard-hw-footprints:TP_SMD_0.75mm" (id 2) (at 248.92 75.184 0)
      (effects (font (size 1.524 1.524)) (justify left) hide)
    )
    (property "Datasheet" "" (id 3) (at 248.92 77.724 0)
      (effects (font (size 1.524 1.524)) (justify left) hide)
    )
    (property "MPN" "" (id 4) (at 236.22 54.864 0)
      (effects (font (size 1.27 1.27) (thickness 0.15)) (justify left bottom) hide)
    )
    (property "Manufacturer" "" (id 5) (at 236.22 52.324 0)
      (effects (font (size 1.27 1.27) (thickness 0.15)) (justify left bottom) hide)
    )
    (property "Author" "Antmicro" (id 6) (at 236.22 49.784 0)
      (effects (font (size 1.27 1.27) (thickness 0.15)) (justify left bottom) hide)
    )
    (property "License" "Apache-2.0" (id 7) (at 236.22 47.244 0)
      (effects (font (size 1.27 1.27) (thickness 0.15)) (justify left bottom) hide)
    )
    (pin "1")
  )

  (symbol (lib_id "sa800u-baseboard-hw:C_100n_0402") (at 104.775 120.65 270) (unit 1)
    (in_bom yes) (on_board yes) (fields_autoplaced)
    (property "Reference" "C123" (id 0) (at 107.315 121.9263 90)
      (effects (font (size 1.524 1.524)) (justify left))
    )
    (property "Value" "C_100n_0402" (id 1) (at 100.965 120.65 0)
      (effects (font (size 1.524 1.524)) hide)
    )
    (property "Footprint" "sa800u-baseboard-hw-footprints:C_0402_1005Metric" (id 2) (at 109.855 125.73 0)
      (effects (font (size 1.524 1.524)) (justify left) hide)
    )
    (property "Datasheet" "https://search.murata.co.jp/Ceramy/image/img/A01X/G101/ENG/GRM155R61H104KE14-01.pdf" (id 3) (at 104.775 120.65 0)
      (effects (font (size 1.27 1.27)) hide)
    )
    (property "Manufacturer" "Murata" (id 4) (at 114.935 125.73 0)
      (effects (font (size 1.524 1.524)) (justify left) hide)
    )
    (property "MPN" "GRM155R61H104KE14D" (id 5) (at 112.395 125.73 0)
      (effects (font (size 1.524 1.524)) (justify left) hide)
    )
    (property "Val" "100n" (id 6) (at 107.315 125.1012 90)
      (effects (font (size 1.27 1.27)) (justify left))
    )
    (property "License" "Apache-2.0" (id 7) (at 81.915 140.97 0)
      (effects (font (size 1.27 1.27) (thickness 0.15)) (justify left bottom) hide)
    )
    (property "Author" "Antmicro" (id 8) (at 79.375 140.97 0)
      (effects (font (size 1.27 1.27) (thickness 0.15)) (justify left bottom) hide)
    )
    (property "Voltage" "50V" (id 9) (at 76.835 140.97 0)
      (effects (font (size 1.27 1.27)) (justify left bottom) hide)
    )
    (property "Dielectric" "X5R" (id 10) (at 74.295 140.97 0)
      (effects (font (size 1.27 1.27)) (justify left bottom) hide)
    )
    (pin "1")
    (pin "2")
  )

  (symbol (lib_id "sa800u-baseboard-hw:C_100n_0402") (at 117.475 120.65 270) (unit 1)
    (in_bom yes) (on_board yes)
    (property "Reference" "C124" (id 0) (at 119.507 121.92 90)
      (effects (font (size 1.524 1.524)) (justify left))
    )
    (property "Value" "C_100n_0402" (id 1) (at 113.665 120.65 0)
      (effects (font (size 1.524 1.524)) hide)
    )
    (property "Footprint" "sa800u-baseboard-hw-footprints:C_0402_1005Metric" (id 2) (at 122.555 125.73 0)
      (effects (font (size 1.524 1.524)) (justify left) hide)
    )
    (property "Datasheet" "https://search.murata.co.jp/Ceramy/image/img/A01X/G101/ENG/GRM155R61H104KE14-01.pdf" (id 3) (at 117.475 120.65 0)
      (effects (font (size 1.27 1.27)) hide)
    )
    (property "Manufacturer" "Murata" (id 4) (at 127.635 125.73 0)
      (effects (font (size 1.524 1.524)) (justify left) hide)
    )
    (property "MPN" "GRM155R61H104KE14D" (id 5) (at 125.095 125.73 0)
      (effects (font (size 1.524 1.524)) (justify left) hide)
    )
    (property "Val" "100n" (id 6) (at 119.507 125.0949 90)
      (effects (font (size 1.27 1.27)) (justify left))
    )
    (property "License" "Apache-2.0" (id 7) (at 94.615 140.97 0)
      (effects (font (size 1.27 1.27) (thickness 0.15)) (justify left bottom) hide)
    )
    (property "Author" "Antmicro" (id 8) (at 92.075 140.97 0)
      (effects (font (size 1.27 1.27) (thickness 0.15)) (justify left bottom) hide)
    )
    (property "Voltage" "50V" (id 9) (at 89.535 140.97 0)
      (effects (font (size 1.27 1.27)) (justify left bottom) hide)
    )
    (property "Dielectric" "X5R" (id 10) (at 86.995 140.97 0)
      (effects (font (size 1.27 1.27)) (justify left bottom) hide)
    )
    (pin "1")
    (pin "2")
  )

  (symbol (lib_id "sa800u-baseboard-hw:C_100n_0402") (at 130.175 118.11 270) (unit 1)
    (in_bom yes) (on_board yes) (fields_autoplaced)
    (property "Reference" "C125" (id 0) (at 133.096 119.3863 90)
      (effects (font (size 1.524 1.524)) (justify left))
    )
    (property "Value" "C_100n_0402" (id 1) (at 126.365 118.11 0)
      (effects (font (size 1.524 1.524)) hide)
    )
    (property "Footprint" "sa800u-baseboard-hw-footprints:C_0402_1005Metric" (id 2) (at 135.255 123.19 0)
      (effects (font (size 1.524 1.524)) (justify left) hide)
    )
    (property "Datasheet" "https://search.murata.co.jp/Ceramy/image/img/A01X/G101/ENG/GRM155R61H104KE14-01.pdf" (id 3) (at 130.175 118.11 0)
      (effects (font (size 1.27 1.27)) hide)
    )
    (property "Manufacturer" "Murata" (id 4) (at 140.335 123.19 0)
      (effects (font (size 1.524 1.524)) (justify left) hide)
    )
    (property "MPN" "GRM155R61H104KE14D" (id 5) (at 137.795 123.19 0)
      (effects (font (size 1.524 1.524)) (justify left) hide)
    )
    (property "Val" "100n" (id 6) (at 133.096 122.5612 90)
      (effects (font (size 1.27 1.27)) (justify left))
    )
    (property "License" "Apache-2.0" (id 7) (at 107.315 138.43 0)
      (effects (font (size 1.27 1.27) (thickness 0.15)) (justify left bottom) hide)
    )
    (property "Author" "Antmicro" (id 8) (at 104.775 138.43 0)
      (effects (font (size 1.27 1.27) (thickness 0.15)) (justify left bottom) hide)
    )
    (property "Voltage" "50V" (id 9) (at 102.235 138.43 0)
      (effects (font (size 1.27 1.27)) (justify left bottom) hide)
    )
    (property "Dielectric" "X5R" (id 10) (at 99.695 138.43 0)
      (effects (font (size 1.27 1.27)) (justify left bottom) hide)
    )
    (pin "1")
    (pin "2")
  )

  (symbol (lib_id "sa800u-baseboard-hw:GND") (at 104.775 125.73 0) (unit 1)
    (in_bom yes) (on_board yes) (fields_autoplaced)
    (property "Reference" "#PWR0204" (id 0) (at 104.775 132.08 0)
      (effects (font (size 1.27 1.27)) hide)
    )
    (property "Value" "GND" (id 1) (at 104.775 130.81 0))
    (property "Footprint" "" (id 2) (at 104.775 125.73 0)
      (effects (font (size 1.27 1.27)) hide)
    )
    (property "Datasheet" "" (id 3) (at 104.775 125.73 0)
      (effects (font (size 1.27 1.27)) hide)
    )
    (property "Author" "Antmicro" (id 4) (at 113.665 133.35 0)
      (effects (font (size 1.27 1.27) (thickness 0.15)) (justify left bottom) hide)
    )
    (property "License" "Apache-2.0" (id 5) (at 113.665 135.89 0)
      (effects (font (size 1.27 1.27) (thickness 0.15)) (justify left bottom) hide)
    )
    (pin "1")
  )

  (symbol (lib_id "sa800u-baseboard-hw:GND") (at 117.475 125.73 0) (unit 1)
    (in_bom yes) (on_board yes) (fields_autoplaced)
    (property "Reference" "#PWR0206" (id 0) (at 117.475 132.08 0)
      (effects (font (size 1.27 1.27)) hide)
    )
    (property "Value" "GND" (id 1) (at 117.475 130.81 0))
    (property "Footprint" "" (id 2) (at 117.475 125.73 0)
      (effects (font (size 1.27 1.27)) hide)
    )
    (property "Datasheet" "" (id 3) (at 117.475 125.73 0)
      (effects (font (size 1.27 1.27)) hide)
    )
    (property "Author" "Antmicro" (id 4) (at 126.365 133.35 0)
      (effects (font (size 1.27 1.27) (thickness 0.15)) (justify left bottom) hide)
    )
    (property "License" "Apache-2.0" (id 5) (at 126.365 135.89 0)
      (effects (font (size 1.27 1.27) (thickness 0.15)) (justify left bottom) hide)
    )
    (pin "1")
  )

  (symbol (lib_id "sa800u-baseboard-hw:GND") (at 130.175 123.19 0) (unit 1)
    (in_bom yes) (on_board yes) (fields_autoplaced)
    (property "Reference" "#PWR0207" (id 0) (at 130.175 129.54 0)
      (effects (font (size 1.27 1.27)) hide)
    )
    (property "Value" "GND" (id 1) (at 130.175 128.27 0))
    (property "Footprint" "" (id 2) (at 130.175 123.19 0)
      (effects (font (size 1.27 1.27)) hide)
    )
    (property "Datasheet" "" (id 3) (at 130.175 123.19 0)
      (effects (font (size 1.27 1.27)) hide)
    )
    (property "Author" "Antmicro" (id 4) (at 139.065 130.81 0)
      (effects (font (size 1.27 1.27) (thickness 0.15)) (justify left bottom) hide)
    )
    (property "License" "Apache-2.0" (id 5) (at 139.065 133.35 0)
      (effects (font (size 1.27 1.27) (thickness 0.15)) (justify left bottom) hide)
    )
    (pin "1")
  )

  (symbol (lib_id "sa800u-baseboard-hw:TP_0.75mm_SMD") (at 263.906 55.88 180) (unit 1)
    (in_bom yes) (on_board yes) (fields_autoplaced)
    (property "Reference" "TP60" (id 0) (at 260.731 52.07 0))
    (property "Value" "TP_0.75mm_SMD" (id 1) (at 263.906 53.34 0)
      (effects (font (size 1.27 1.27)) hide)
    )
    (property "Footprint" "sa800u-baseboard-hw-footprints:TP_SMD_0.75mm" (id 2) (at 258.826 60.96 0)
      (effects (font (size 1.524 1.524)) (justify left) hide)
    )
    (property "Datasheet" "" (id 3) (at 258.826 63.5 0)
      (effects (font (size 1.524 1.524)) (justify left) hide)
    )
    (property "MPN" "" (id 4) (at 246.126 40.64 0)
      (effects (font (size 1.27 1.27) (thickness 0.15)) (justify left bottom) hide)
    )
    (property "Manufacturer" "" (id 5) (at 246.126 38.1 0)
      (effects (font (size 1.27 1.27) (thickness 0.15)) (justify left bottom) hide)
    )
    (property "Author" "Antmicro" (id 6) (at 246.126 35.56 0)
      (effects (font (size 1.27 1.27) (thickness 0.15)) (justify left bottom) hide)
    )
    (property "License" "Apache-2.0" (id 7) (at 246.126 33.02 0)
      (effects (font (size 1.27 1.27) (thickness 0.15)) (justify left bottom) hide)
    )
    (pin "1")
  )

  (symbol (lib_id "sa800u-baseboard-hw:R_10k_0402") (at 283.972 191.77 0) (unit 1)
    (in_bom yes) (on_board yes)
    (property "Reference" "R132" (id 0) (at 285.877 187.96 0)
      (effects (font (size 1.524 1.524)))
    )
    (property "Value" "R_10k_0402" (id 1) (at 283.972 195.58 0)
      (effects (font (size 1.524 1.524)) hide)
    )
    (property "Footprint" "sa800u-baseboard-hw-footprints:R_0402_1005Metric" (id 2) (at 289.052 186.69 0)
      (effects (font (size 1.524 1.524)) (justify left) hide)
    )
    (property "Datasheet" "https://www.bourns.com/docs/product-datasheets/cr.pdf" (id 3) (at 283.972 191.77 0)
      (effects (font (size 1.27 1.27)) hide)
    )
    (property "Manufacturer" "Bourns" (id 4) (at 289.052 181.61 0)
      (effects (font (size 1.524 1.524)) (justify left) hide)
    )
    (property "MPN" "CR0402-FX-1002GLF" (id 5) (at 289.052 184.15 0)
      (effects (font (size 1.524 1.524)) (justify left) hide)
    )
    (property "Val" "10k" (id 6) (at 285.877 189.865 0))
    (property "DNP" "DNP" (id 7) (at 286.512 191.77 0))
    (property "License" "Apache-2.0" (id 8) (at 304.292 217.17 0)
      (effects (font (size 1.27 1.27) (thickness 0.15)) (justify left bottom) hide)
    )
    (property "Author" "Antmicro" (id 9) (at 304.292 219.71 0)
      (effects (font (size 1.27 1.27) (thickness 0.15)) (justify left bottom) hide)
    )
    (property "Tolerance" "1%" (id 10) (at 304.292 201.93 0)
      (effects (font (size 1.27 1.27)) (justify left bottom) hide)
    )
    (pin "1")
    (pin "2")
  )

  (symbol (lib_id "sa800u-baseboard-hw:R_10k_0402") (at 271.145 194.31 0) (unit 1)
    (in_bom yes) (on_board yes) (fields_autoplaced)
    (property "Reference" "R127" (id 0) (at 273.685 198.12 0)
      (effects (font (size 1.524 1.524)))
    )
    (property "Value" "R_10k_0402" (id 1) (at 271.145 198.12 0)
      (effects (font (size 1.524 1.524)) hide)
    )
    (property "Footprint" "sa800u-baseboard-hw-footprints:R_0402_1005Metric" (id 2) (at 276.225 189.23 0)
      (effects (font (size 1.524 1.524)) (justify left) hide)
    )
    (property "Datasheet" "https://www.bourns.com/docs/product-datasheets/cr.pdf" (id 3) (at 271.145 194.31 0)
      (effects (font (size 1.27 1.27)) hide)
    )
    (property "Manufacturer" "Bourns" (id 4) (at 276.225 184.15 0)
      (effects (font (size 1.524 1.524)) (justify left) hide)
    )
    (property "MPN" "CR0402-FX-1002GLF" (id 5) (at 276.225 186.69 0)
      (effects (font (size 1.524 1.524)) (justify left) hide)
    )
    (property "Val" "10k" (id 6) (at 273.685 201.93 0))
    (property "License" "Apache-2.0" (id 7) (at 291.465 219.71 0)
      (effects (font (size 1.27 1.27) (thickness 0.15)) (justify left bottom) hide)
    )
    (property "Author" "Antmicro" (id 8) (at 291.465 222.25 0)
      (effects (font (size 1.27 1.27) (thickness 0.15)) (justify left bottom) hide)
    )
    (property "Tolerance" "1%" (id 9) (at 291.465 204.47 0)
      (effects (font (size 1.27 1.27)) (justify left bottom) hide)
    )
    (pin "1")
    (pin "2")
  )

  (symbol (lib_id "sa800u-baseboard-hw:R_10k_0402") (at 284.226 226.695 0) (unit 1)
    (in_bom yes) (on_board yes)
    (property "Reference" "R133" (id 0) (at 286.258 224.155 0)
      (effects (font (size 1.524 1.524)))
    )
    (property "Value" "R_10k_0402" (id 1) (at 284.226 230.505 0)
      (effects (font (size 1.524 1.524)) hide)
    )
    (property "Footprint" "sa800u-baseboard-hw-footprints:R_0402_1005Metric" (id 2) (at 289.306 221.615 0)
      (effects (font (size 1.524 1.524)) (justify left) hide)
    )
    (property "Datasheet" "https://www.bourns.com/docs/product-datasheets/cr.pdf" (id 3) (at 284.226 226.695 0)
      (effects (font (size 1.27 1.27)) hide)
    )
    (property "Manufacturer" "Bourns" (id 4) (at 289.306 216.535 0)
      (effects (font (size 1.524 1.524)) (justify left) hide)
    )
    (property "MPN" "CR0402-FX-1002GLF" (id 5) (at 289.306 219.075 0)
      (effects (font (size 1.524 1.524)) (justify left) hide)
    )
    (property "Val" "10k" (id 6) (at 286.766 228.6 0))
    (property "DNP" "DNP" (id 7) (at 286.766 226.695 0))
    (property "License" "Apache-2.0" (id 8) (at 304.546 252.095 0)
      (effects (font (size 1.27 1.27) (thickness 0.15)) (justify left bottom) hide)
    )
    (property "Author" "Antmicro" (id 9) (at 304.546 254.635 0)
      (effects (font (size 1.27 1.27) (thickness 0.15)) (justify left bottom) hide)
    )
    (property "Tolerance" "1%" (id 10) (at 304.546 236.855 0)
      (effects (font (size 1.27 1.27)) (justify left bottom) hide)
    )
    (pin "1")
    (pin "2")
  )

  (symbol (lib_id "sa800u-baseboard-hw:R_10k_0402") (at 269.24 229.997 0) (unit 1)
    (in_bom yes) (on_board yes) (fields_autoplaced)
    (property "Reference" "R128" (id 0) (at 271.78 234.442 0)
      (effects (font (size 1.524 1.524)))
    )
    (property "Value" "R_10k_0402" (id 1) (at 269.24 233.807 0)
      (effects (font (size 1.524 1.524)) hide)
    )
    (property "Footprint" "sa800u-baseboard-hw-footprints:R_0402_1005Metric" (id 2) (at 274.32 224.917 0)
      (effects (font (size 1.524 1.524)) (justify left) hide)
    )
    (property "Datasheet" "https://www.bourns.com/docs/product-datasheets/cr.pdf" (id 3) (at 269.24 229.997 0)
      (effects (font (size 1.27 1.27)) hide)
    )
    (property "Manufacturer" "Bourns" (id 4) (at 274.32 219.837 0)
      (effects (font (size 1.524 1.524)) (justify left) hide)
    )
    (property "MPN" "CR0402-FX-1002GLF" (id 5) (at 274.32 222.377 0)
      (effects (font (size 1.524 1.524)) (justify left) hide)
    )
    (property "Val" "10k" (id 6) (at 271.78 236.982 0))
    (property "License" "Apache-2.0" (id 7) (at 289.56 255.397 0)
      (effects (font (size 1.27 1.27) (thickness 0.15)) (justify left bottom) hide)
    )
    (property "Author" "Antmicro" (id 8) (at 289.56 257.937 0)
      (effects (font (size 1.27 1.27) (thickness 0.15)) (justify left bottom) hide)
    )
    (property "Tolerance" "1%" (id 9) (at 289.56 240.157 0)
      (effects (font (size 1.27 1.27)) (justify left bottom) hide)
    )
    (pin "1")
    (pin "2")
  )

  (symbol (lib_id "sa800u-baseboard-hw:R_75k_0402") (at 336.55 153.035 270) (unit 1)
    (in_bom yes) (on_board yes) (fields_autoplaced)
    (property "Reference" "R135" (id 0) (at 339.09 154.305 90)
      (effects (font (size 1.524 1.524)) (justify left))
    )
    (property "Value" "R_75k_0402" (id 1) (at 332.74 153.035 0)
      (effects (font (size 1.524 1.524)) hide)
    )
    (property "Footprint" "sa800u-baseboard-hw-footprints:R_0402_1005Metric" (id 2) (at 341.63 158.115 0)
      (effects (font (size 1.524 1.524)) (justify left) hide)
    )
    (property "Datasheet" "https://www.bourns.com/docs/product-datasheets/cr.pdf" (id 3) (at 336.55 153.035 0)
      (effects (font (size 1.27 1.27)) hide)
    )
    (property "Manufacturer" "Bourns" (id 4) (at 346.71 158.115 0)
      (effects (font (size 1.524 1.524)) (justify left) hide)
    )
    (property "MPN" "CR0402-FX-7502GLF" (id 5) (at 344.17 158.115 0)
      (effects (font (size 1.524 1.524)) (justify left) hide)
    )
    (property "Val" "75k" (id 6) (at 339.09 157.4799 90)
      (effects (font (size 1.27 1.27)) (justify left))
    )
    (property "License" "Apache-2.0" (id 7) (at 311.15 173.355 0)
      (effects (font (size 1.27 1.27) (thickness 0.15)) (justify left bottom) hide)
    )
    (property "Author" "Antmicro" (id 8) (at 308.61 173.355 0)
      (effects (font (size 1.27 1.27) (thickness 0.15)) (justify left bottom) hide)
    )
    (property "Tolerance" "1%" (id 9) (at 326.39 173.355 0)
      (effects (font (size 1.27 1.27)) (justify left bottom) hide)
    )
    (pin "1")
    (pin "2")
  )

  (symbol (lib_id "sa800u-baseboard-hw:LED_G_0603_KP-1608ZGC") (at 80.01 245.745 0) (unit 1)
    (in_bom yes) (on_board yes) (fields_autoplaced)
    (property "Reference" "D24" (id 0) (at 83.82 241.3 0)
      (effects (font (size 1.524 1.524)))
    )
    (property "Value" "KP-1608EC" (id 1) (at 78.74 239.8776 0)
      (effects (font (size 1.524 1.524)) hide)
    )
    (property "Footprint" "sa800u-baseboard-hw-footprints:LED_0603_1608Metric_G" (id 2) (at 102.87 255.905 0)
      (effects (font (size 1.27 1.27) (thickness 0.15)) (justify left bottom) hide)
    )
    (property "Datasheet" "https://www.farnell.com/datasheets/2045914.pdf" (id 3) (at 102.87 258.445 0)
      (effects (font (size 1.27 1.27) (thickness 0.15)) (justify left bottom) hide)
    )
    (property "MPN" "KP-1608ZGC" (id 4) (at 102.87 260.985 0)
      (effects (font (size 1.27 1.27) (thickness 0.15)) (justify left bottom) hide)
    )
    (property "Manufacturer" "Kingbright" (id 5) (at 102.87 263.525 0)
      (effects (font (size 1.27 1.27) (thickness 0.15)) (justify left bottom) hide)
    )
    (property "Author" "Antmicro" (id 6) (at 102.87 266.065 0)
      (effects (font (size 1.27 1.27) (thickness 0.15)) (justify left bottom) hide)
    )
    (property "License" "Apache-2.0" (id 7) (at 102.87 268.605 0)
      (effects (font (size 1.27 1.27) (thickness 0.15)) (justify left bottom) hide)
    )
    (pin "1")
    (pin "2")
  )

  (symbol (lib_id "sa800u-baseboard-hw:GND") (at 109.22 205.74 0) (unit 1)
    (in_bom yes) (on_board yes) (fields_autoplaced)
    (property "Reference" "#PWR0209" (id 0) (at 109.22 212.09 0)
      (effects (font (size 1.27 1.27)) hide)
    )
    (property "Value" "GND" (id 1) (at 109.22 210.82 0))
    (property "Footprint" "" (id 2) (at 109.22 205.74 0)
      (effects (font (size 1.27 1.27)) hide)
    )
    (property "Datasheet" "" (id 3) (at 109.22 205.74 0)
      (effects (font (size 1.27 1.27)) hide)
    )
    (property "Author" "Antmicro" (id 4) (at 118.11 213.36 0)
      (effects (font (size 1.27 1.27) (thickness 0.15)) (justify left bottom) hide)
    )
    (property "License" "Apache-2.0" (id 5) (at 118.11 215.9 0)
      (effects (font (size 1.27 1.27) (thickness 0.15)) (justify left bottom) hide)
    )
    (pin "1")
  )

  (symbol (lib_id "sa800u-baseboard-hw:LED_G_0603_KP-1608ZGC") (at 119.38 245.745 0) (unit 1)
    (in_bom yes) (on_board yes) (fields_autoplaced)
    (property "Reference" "D25" (id 0) (at 123.19 241.3 0)
      (effects (font (size 1.524 1.524)))
    )
    (property "Value" "KP-1608EC" (id 1) (at 118.11 239.8776 0)
      (effects (font (size 1.524 1.524)) hide)
    )
    (property "Footprint" "sa800u-baseboard-hw-footprints:LED_0603_1608Metric_G" (id 2) (at 142.24 255.905 0)
      (effects (font (size 1.27 1.27) (thickness 0.15)) (justify left bottom) hide)
    )
    (property "Datasheet" "https://www.farnell.com/datasheets/2045914.pdf" (id 3) (at 142.24 258.445 0)
      (effects (font (size 1.27 1.27) (thickness 0.15)) (justify left bottom) hide)
    )
    (property "MPN" "KP-1608ZGC" (id 4) (at 142.24 260.985 0)
      (effects (font (size 1.27 1.27) (thickness 0.15)) (justify left bottom) hide)
    )
    (property "Manufacturer" "Kingbright" (id 5) (at 142.24 263.525 0)
      (effects (font (size 1.27 1.27) (thickness 0.15)) (justify left bottom) hide)
    )
    (property "Author" "Antmicro" (id 6) (at 142.24 266.065 0)
      (effects (font (size 1.27 1.27) (thickness 0.15)) (justify left bottom) hide)
    )
    (property "License" "Apache-2.0" (id 7) (at 142.24 268.605 0)
      (effects (font (size 1.27 1.27) (thickness 0.15)) (justify left bottom) hide)
    )
    (pin "1")
    (pin "2")
  )

  (symbol (lib_id "sa800u-baseboard-hw:R_13k7_0402") (at 74.295 161.671 270) (unit 1)
    (in_bom yes) (on_board yes) (fields_autoplaced)
    (property "Reference" "R114" (id 0) (at 76.2 162.941 90)
      (effects (font (size 1.524 1.524)) (justify left))
    )
    (property "Value" "R_13k7_0402" (id 1) (at 70.485 161.671 0)
      (effects (font (size 1.524 1.524)) hide)
    )
    (property "Footprint" "sa800u-baseboard-hw-footprints:R_0402_1005Metric" (id 2) (at 79.375 166.751 0)
      (effects (font (size 1.524 1.524)) (justify left) hide)
    )
    (property "Datasheet" "https://www.bourns.com/docs/product-datasheets/cr.pdf" (id 3) (at 74.295 161.671 0)
      (effects (font (size 1.27 1.27)) hide)
    )
    (property "Manufacturer" "Bourns" (id 4) (at 84.455 166.751 0)
      (effects (font (size 1.524 1.524)) (justify left) hide)
    )
    (property "MPN" "CR0402-FX-1372GLF" (id 5) (at 81.915 166.751 0)
      (effects (font (size 1.524 1.524)) (justify left) hide)
    )
    (property "Val" "13k7" (id 6) (at 76.2 166.1159 90)
      (effects (font (size 1.27 1.27)) (justify left))
    )
    (property "License" "Apache-2.0" (id 7) (at 48.895 181.991 0)
      (effects (font (size 1.27 1.27) (thickness 0.15)) (justify left bottom) hide)
    )
    (property "Author" "Antmicro" (id 8) (at 46.355 181.991 0)
      (effects (font (size 1.27 1.27) (thickness 0.15)) (justify left bottom) hide)
    )
    (property "Tolerance" "1%" (id 9) (at 64.135 181.991 0)
      (effects (font (size 1.27 1.27)) (justify left bottom) hide)
    )
    (pin "1")
    (pin "2")
  )

  (symbol (lib_id "sa800u-baseboard-hw:LED_G_0603_KP-1608ZGC") (at 160.655 246.38 0) (unit 1)
    (in_bom yes) (on_board yes) (fields_autoplaced)
    (property "Reference" "D26" (id 0) (at 164.465 242.57 0)
      (effects (font (size 1.524 1.524)))
    )
    (property "Value" "KP-1608EC" (id 1) (at 159.385 240.5126 0)
      (effects (font (size 1.524 1.524)) hide)
    )
    (property "Footprint" "sa800u-baseboard-hw-footprints:LED_0603_1608Metric_G" (id 2) (at 183.515 256.54 0)
      (effects (font (size 1.27 1.27) (thickness 0.15)) (justify left bottom) hide)
    )
    (property "Datasheet" "https://www.farnell.com/datasheets/2045914.pdf" (id 3) (at 183.515 259.08 0)
      (effects (font (size 1.27 1.27) (thickness 0.15)) (justify left bottom) hide)
    )
    (property "MPN" "KP-1608ZGC" (id 4) (at 183.515 261.62 0)
      (effects (font (size 1.27 1.27) (thickness 0.15)) (justify left bottom) hide)
    )
    (property "Manufacturer" "Kingbright" (id 5) (at 183.515 264.16 0)
      (effects (font (size 1.27 1.27) (thickness 0.15)) (justify left bottom) hide)
    )
    (property "Author" "Antmicro" (id 6) (at 183.515 266.7 0)
      (effects (font (size 1.27 1.27) (thickness 0.15)) (justify left bottom) hide)
    )
    (property "License" "Apache-2.0" (id 7) (at 183.515 269.24 0)
      (effects (font (size 1.27 1.27) (thickness 0.15)) (justify left bottom) hide)
    )
    (pin "1")
    (pin "2")
  )

  (symbol (lib_id "sa800u-baseboard-hw:R_13k7_0402") (at 66.675 188.341 270) (unit 1)
    (in_bom yes) (on_board yes) (fields_autoplaced)
    (property "Reference" "R110" (id 0) (at 68.58 189.611 90)
      (effects (font (size 1.524 1.524)) (justify left))
    )
    (property "Value" "R_13k7_0402" (id 1) (at 62.865 188.341 0)
      (effects (font (size 1.524 1.524)) hide)
    )
    (property "Footprint" "sa800u-baseboard-hw-footprints:R_0402_1005Metric" (id 2) (at 71.755 193.421 0)
      (effects (font (size 1.524 1.524)) (justify left) hide)
    )
    (property "Datasheet" "https://www.bourns.com/docs/product-datasheets/cr.pdf" (id 3) (at 66.675 188.341 0)
      (effects (font (size 1.27 1.27)) hide)
    )
    (property "Manufacturer" "Bourns" (id 4) (at 76.835 193.421 0)
      (effects (font (size 1.524 1.524)) (justify left) hide)
    )
    (property "MPN" "CR0402-FX-1372GLF" (id 5) (at 74.295 193.421 0)
      (effects (font (size 1.524 1.524)) (justify left) hide)
    )
    (property "Val" "13k7" (id 6) (at 68.58 192.7859 90)
      (effects (font (size 1.27 1.27)) (justify left))
    )
    (property "License" "Apache-2.0" (id 7) (at 41.275 208.661 0)
      (effects (font (size 1.27 1.27) (thickness 0.15)) (justify left bottom) hide)
    )
    (property "Author" "Antmicro" (id 8) (at 38.735 208.661 0)
      (effects (font (size 1.27 1.27) (thickness 0.15)) (justify left bottom) hide)
    )
    (property "Tolerance" "1%" (id 9) (at 56.515 208.661 0)
      (effects (font (size 1.27 1.27)) (justify left bottom) hide)
    )
    (pin "1")
    (pin "2")
  )

  (symbol (lib_id "sa800u-baseboard-hw:R_255k_0402") (at 109.22 200.66 270) (unit 1)
    (in_bom yes) (on_board yes) (fields_autoplaced)
    (property "Reference" "R117" (id 0) (at 111.76 201.93 90)
      (effects (font (size 1.524 1.524)) (justify left))
    )
    (property "Value" "R_255k_0402" (id 1) (at 105.41 200.66 0)
      (effects (font (size 1.524 1.524)) hide)
    )
    (property "Footprint" "sa800u-baseboard-hw-footprints:R_0402_1005Metric" (id 2) (at 114.3 205.74 0)
      (effects (font (size 1.524 1.524)) (justify left) hide)
    )
    (property "Datasheet" "https://www.bourns.com/docs/product-datasheets/cr.pdf" (id 3) (at 109.22 200.66 0)
      (effects (font (size 1.27 1.27)) hide)
    )
    (property "Manufacturer" "Bourns" (id 4) (at 119.38 205.74 0)
      (effects (font (size 1.524 1.524)) (justify left) hide)
    )
    (property "MPN" "CR0402-FX-2553GLF" (id 5) (at 116.84 205.74 0)
      (effects (font (size 1.524 1.524)) (justify left) hide)
    )
    (property "Val" "255k" (id 6) (at 111.76 205.1049 90)
      (effects (font (size 1.27 1.27)) (justify left))
    )
    (property "License" "Apache-2.0" (id 7) (at 83.82 220.98 0)
      (effects (font (size 1.27 1.27) (thickness 0.15)) (justify left bottom) hide)
    )
    (property "Author" "Antmicro" (id 8) (at 81.28 220.98 0)
      (effects (font (size 1.27 1.27) (thickness 0.15)) (justify left bottom) hide)
    )
    (property "Tolerance" "1%" (id 9) (at 99.06 220.98 0)
      (effects (font (size 1.27 1.27)) (justify left bottom) hide)
    )
    (pin "1")
    (pin "2")
  )

  (symbol (lib_id "sa800u-baseboard-hw:R_13k7_0402") (at 59.055 215.011 270) (unit 1)
    (in_bom yes) (on_board yes) (fields_autoplaced)
    (property "Reference" "R107" (id 0) (at 57.15 216.281 90)
      (effects (font (size 1.524 1.524)) (justify right))
    )
    (property "Value" "R_13k7_0402" (id 1) (at 55.245 215.011 0)
      (effects (font (size 1.524 1.524)) hide)
    )
    (property "Footprint" "sa800u-baseboard-hw-footprints:R_0402_1005Metric" (id 2) (at 64.135 220.091 0)
      (effects (font (size 1.524 1.524)) (justify left) hide)
    )
    (property "Datasheet" "https://www.bourns.com/docs/product-datasheets/cr.pdf" (id 3) (at 59.055 215.011 0)
      (effects (font (size 1.27 1.27)) hide)
    )
    (property "Manufacturer" "Bourns" (id 4) (at 69.215 220.091 0)
      (effects (font (size 1.524 1.524)) (justify left) hide)
    )
    (property "MPN" "CR0402-FX-1372GLF" (id 5) (at 66.675 220.091 0)
      (effects (font (size 1.524 1.524)) (justify left) hide)
    )
    (property "Val" "13k7" (id 6) (at 57.15 219.4559 90)
      (effects (font (size 1.27 1.27)) (justify right))
    )
    (property "License" "Apache-2.0" (id 7) (at 33.655 235.331 0)
      (effects (font (size 1.27 1.27) (thickness 0.15)) (justify left bottom) hide)
    )
    (property "Author" "Antmicro" (id 8) (at 31.115 235.331 0)
      (effects (font (size 1.27 1.27) (thickness 0.15)) (justify left bottom) hide)
    )
    (property "Tolerance" "1%" (id 9) (at 48.895 235.331 0)
      (effects (font (size 1.27 1.27)) (justify left bottom) hide)
    )
    (pin "1")
    (pin "2")
  )

  (symbol (lib_id "sa800u-baseboard-hw:GND") (at 66.675 223.52 0) (unit 1)
    (in_bom yes) (on_board yes) (fields_autoplaced)
    (property "Reference" "#PWR0200" (id 0) (at 66.675 229.87 0)
      (effects (font (size 1.27 1.27)) hide)
    )
    (property "Value" "GND" (id 1) (at 66.675 228.6 0))
    (property "Footprint" "" (id 2) (at 66.675 223.52 0)
      (effects (font (size 1.27 1.27)) hide)
    )
    (property "Datasheet" "" (id 3) (at 66.675 223.52 0)
      (effects (font (size 1.27 1.27)) hide)
    )
    (property "Author" "Antmicro" (id 4) (at 75.565 231.14 0)
      (effects (font (size 1.27 1.27) (thickness 0.15)) (justify left bottom) hide)
    )
    (property "License" "Apache-2.0" (id 5) (at 75.565 233.68 0)
      (effects (font (size 1.27 1.27) (thickness 0.15)) (justify left bottom) hide)
    )
    (pin "1")
  )

  (symbol (lib_id "sa800u-baseboard-hw:R_39k_0402") (at 74.295 152.781 270) (unit 1)
    (in_bom yes) (on_board yes) (fields_autoplaced)
    (property "Reference" "R113" (id 0) (at 76.2 154.051 90)
      (effects (font (size 1.524 1.524)) (justify left))
    )
    (property "Value" "R_39k_0402" (id 1) (at 70.485 152.781 0)
      (effects (font (size 1.524 1.524)) hide)
    )
    (property "Footprint" "sa800u-baseboard-hw-footprints:R_0402_1005Metric" (id 2) (at 79.375 157.861 0)
      (effects (font (size 1.524 1.524)) (justify left) hide)
    )
    (property "Datasheet" "https://www.bourns.com/docs/product-datasheets/cr.pdf" (id 3) (at 74.295 152.781 0)
      (effects (font (size 1.27 1.27)) hide)
    )
    (property "Manufacturer" "Bourns" (id 4) (at 84.455 157.861 0)
      (effects (font (size 1.524 1.524)) (justify left) hide)
    )
    (property "MPN" "CR0402-FX-3902GLF" (id 5) (at 81.915 157.861 0)
      (effects (font (size 1.524 1.524)) (justify left) hide)
    )
    (property "Val" "39k" (id 6) (at 76.2 157.2259 90)
      (effects (font (size 1.27 1.27)) (justify left))
    )
    (property "License" "Apache-2.0" (id 7) (at 48.895 173.101 0)
      (effects (font (size 1.27 1.27) (thickness 0.15)) (justify left bottom) hide)
    )
    (property "Author" "Antmicro" (id 8) (at 46.355 173.101 0)
      (effects (font (size 1.27 1.27) (thickness 0.15)) (justify left bottom) hide)
    )
    (property "Tolerance" "1%" (id 9) (at 64.135 173.101 0)
      (effects (font (size 1.27 1.27)) (justify left bottom) hide)
    )
    (pin "1")
    (pin "2")
  )

  (symbol (lib_id "sa800u-baseboard-hw:R_200k_0402") (at 74.295 143.891 270) (unit 1)
    (in_bom yes) (on_board yes) (fields_autoplaced)
    (property "Reference" "R112" (id 0) (at 76.2 145.161 90)
      (effects (font (size 1.524 1.524)) (justify left))
    )
    (property "Value" "R_200k_0402" (id 1) (at 70.485 143.891 0)
      (effects (font (size 1.524 1.524)) hide)
    )
    (property "Footprint" "sa800u-baseboard-hw-footprints:R_0402_1005Metric" (id 2) (at 79.375 148.971 0)
      (effects (font (size 1.524 1.524)) (justify left) hide)
    )
    (property "Datasheet" "https://www.bourns.com/docs/product-datasheets/cr.pdf" (id 3) (at 74.295 143.891 0)
      (effects (font (size 1.27 1.27)) hide)
    )
    (property "Manufacturer" "Bourns" (id 4) (at 84.455 148.971 0)
      (effects (font (size 1.524 1.524)) (justify left) hide)
    )
    (property "MPN" "CR0402-FX-2003GLF" (id 5) (at 81.915 148.971 0)
      (effects (font (size 1.524 1.524)) (justify left) hide)
    )
    (property "Val" "200k" (id 6) (at 76.2 148.3359 90)
      (effects (font (size 1.27 1.27)) (justify left))
    )
    (property "License" "Apache-2.0" (id 7) (at 48.895 164.211 0)
      (effects (font (size 1.27 1.27) (thickness 0.15)) (justify left bottom) hide)
    )
    (property "Author" "Antmicro" (id 8) (at 46.355 164.211 0)
      (effects (font (size 1.27 1.27) (thickness 0.15)) (justify left bottom) hide)
    )
    (property "Tolerance" "1%" (id 9) (at 64.135 164.211 0)
      (effects (font (size 1.27 1.27)) (justify left bottom) hide)
    )
    (pin "1")
    (pin "2")
  )

  (symbol (lib_id "sa800u-baseboard-hw:R_39k_0402") (at 59.055 206.121 270) (unit 1)
    (in_bom yes) (on_board yes) (fields_autoplaced)
    (property "Reference" "R106" (id 0) (at 60.96 207.391 90)
      (effects (font (size 1.524 1.524)) (justify left))
    )
    (property "Value" "R_39k_0402" (id 1) (at 55.245 206.121 0)
      (effects (font (size 1.524 1.524)) hide)
    )
    (property "Footprint" "sa800u-baseboard-hw-footprints:R_0402_1005Metric" (id 2) (at 64.135 211.201 0)
      (effects (font (size 1.524 1.524)) (justify left) hide)
    )
    (property "Datasheet" "https://www.bourns.com/docs/product-datasheets/cr.pdf" (id 3) (at 59.055 206.121 0)
      (effects (font (size 1.27 1.27)) hide)
    )
    (property "Manufacturer" "Bourns" (id 4) (at 69.215 211.201 0)
      (effects (font (size 1.524 1.524)) (justify left) hide)
    )
    (property "MPN" "CR0402-FX-3902GLF" (id 5) (at 66.675 211.201 0)
      (effects (font (size 1.524 1.524)) (justify left) hide)
    )
    (property "Val" "39k" (id 6) (at 60.96 210.5659 90)
      (effects (font (size 1.27 1.27)) (justify left))
    )
    (property "License" "Apache-2.0" (id 7) (at 33.655 226.441 0)
      (effects (font (size 1.27 1.27) (thickness 0.15)) (justify left bottom) hide)
    )
    (property "Author" "Antmicro" (id 8) (at 31.115 226.441 0)
      (effects (font (size 1.27 1.27) (thickness 0.15)) (justify left bottom) hide)
    )
    (property "Tolerance" "1%" (id 9) (at 48.895 226.441 0)
      (effects (font (size 1.27 1.27)) (justify left bottom) hide)
    )
    (pin "1")
    (pin "2")
  )

  (symbol (lib_id "sa800u-baseboard-hw:R_200k_0402") (at 59.055 197.231 270) (unit 1)
    (in_bom yes) (on_board yes) (fields_autoplaced)
    (property "Reference" "R105" (id 0) (at 60.96 198.501 90)
      (effects (font (size 1.524 1.524)) (justify left))
    )
    (property "Value" "R_200k_0402" (id 1) (at 55.245 197.231 0)
      (effects (font (size 1.524 1.524)) hide)
    )
    (property "Footprint" "sa800u-baseboard-hw-footprints:R_0402_1005Metric" (id 2) (at 64.135 202.311 0)
      (effects (font (size 1.524 1.524)) (justify left) hide)
    )
    (property "Datasheet" "https://www.bourns.com/docs/product-datasheets/cr.pdf" (id 3) (at 59.055 197.231 0)
      (effects (font (size 1.27 1.27)) hide)
    )
    (property "Manufacturer" "Bourns" (id 4) (at 69.215 202.311 0)
      (effects (font (size 1.524 1.524)) (justify left) hide)
    )
    (property "MPN" "CR0402-FX-2003GLF" (id 5) (at 66.675 202.311 0)
      (effects (font (size 1.524 1.524)) (justify left) hide)
    )
    (property "Val" "200k" (id 6) (at 60.96 201.6759 90)
      (effects (font (size 1.27 1.27)) (justify left))
    )
    (property "License" "Apache-2.0" (id 7) (at 33.655 217.551 0)
      (effects (font (size 1.27 1.27) (thickness 0.15)) (justify left bottom) hide)
    )
    (property "Author" "Antmicro" (id 8) (at 31.115 217.551 0)
      (effects (font (size 1.27 1.27) (thickness 0.15)) (justify left bottom) hide)
    )
    (property "Tolerance" "1%" (id 9) (at 48.895 217.551 0)
      (effects (font (size 1.27 1.27)) (justify left bottom) hide)
    )
    (pin "1")
    (pin "2")
  )

  (symbol (lib_id "sa800u-baseboard-hw:R_39k_0402") (at 66.675 179.451 270) (unit 1)
    (in_bom yes) (on_board yes) (fields_autoplaced)
    (property "Reference" "R109" (id 0) (at 68.58 180.721 90)
      (effects (font (size 1.524 1.524)) (justify left))
    )
    (property "Value" "R_39k_0402" (id 1) (at 62.865 179.451 0)
      (effects (font (size 1.524 1.524)) hide)
    )
    (property "Footprint" "sa800u-baseboard-hw-footprints:R_0402_1005Metric" (id 2) (at 71.755 184.531 0)
      (effects (font (size 1.524 1.524)) (justify left) hide)
    )
    (property "Datasheet" "https://www.bourns.com/docs/product-datasheets/cr.pdf" (id 3) (at 66.675 179.451 0)
      (effects (font (size 1.27 1.27)) hide)
    )
    (property "Manufacturer" "Bourns" (id 4) (at 76.835 184.531 0)
      (effects (font (size 1.524 1.524)) (justify left) hide)
    )
    (property "MPN" "CR0402-FX-3902GLF" (id 5) (at 74.295 184.531 0)
      (effects (font (size 1.524 1.524)) (justify left) hide)
    )
    (property "Val" "39k" (id 6) (at 68.58 183.8959 90)
      (effects (font (size 1.27 1.27)) (justify left))
    )
    (property "License" "Apache-2.0" (id 7) (at 41.275 199.771 0)
      (effects (font (size 1.27 1.27) (thickness 0.15)) (justify left bottom) hide)
    )
    (property "Author" "Antmicro" (id 8) (at 38.735 199.771 0)
      (effects (font (size 1.27 1.27) (thickness 0.15)) (justify left bottom) hide)
    )
    (property "Tolerance" "1%" (id 9) (at 56.515 199.771 0)
      (effects (font (size 1.27 1.27)) (justify left bottom) hide)
    )
    (pin "1")
    (pin "2")
  )

  (symbol (lib_id "sa800u-baseboard-hw:R_200k_0402") (at 66.675 170.561 270) (unit 1)
    (in_bom yes) (on_board yes) (fields_autoplaced)
    (property "Reference" "R108" (id 0) (at 68.58 171.831 90)
      (effects (font (size 1.524 1.524)) (justify left))
    )
    (property "Value" "R_200k_0402" (id 1) (at 62.865 170.561 0)
      (effects (font (size 1.524 1.524)) hide)
    )
    (property "Footprint" "sa800u-baseboard-hw-footprints:R_0402_1005Metric" (id 2) (at 71.755 175.641 0)
      (effects (font (size 1.524 1.524)) (justify left) hide)
    )
    (property "Datasheet" "https://www.bourns.com/docs/product-datasheets/cr.pdf" (id 3) (at 66.675 170.561 0)
      (effects (font (size 1.27 1.27)) hide)
    )
    (property "Manufacturer" "Bourns" (id 4) (at 76.835 175.641 0)
      (effects (font (size 1.524 1.524)) (justify left) hide)
    )
    (property "MPN" "CR0402-FX-2003GLF" (id 5) (at 74.295 175.641 0)
      (effects (font (size 1.524 1.524)) (justify left) hide)
    )
    (property "Val" "200k" (id 6) (at 68.58 175.0059 90)
      (effects (font (size 1.27 1.27)) (justify left))
    )
    (property "License" "Apache-2.0" (id 7) (at 41.275 190.881 0)
      (effects (font (size 1.27 1.27) (thickness 0.15)) (justify left bottom) hide)
    )
    (property "Author" "Antmicro" (id 8) (at 38.735 190.881 0)
      (effects (font (size 1.27 1.27) (thickness 0.15)) (justify left bottom) hide)
    )
    (property "Tolerance" "1%" (id 9) (at 56.515 190.881 0)
      (effects (font (size 1.27 1.27)) (justify left bottom) hide)
    )
    (pin "1")
    (pin "2")
  )

  (symbol (lib_id "sa800u-baseboard-hw:BSS84") (at 88.9 250.825 0) (mirror x) (unit 1)
    (in_bom yes) (on_board yes) (fields_autoplaced)
    (property "Reference" "Q8" (id 0) (at 100.33 252.095 0)
      (effects (font (size 1.524 1.524)) (justify left))
    )
    (property "Value" "BSS84" (id 1) (at 100.33 255.905 0)
      (effects (font (size 1.524 1.524)) (justify left))
    )
    (property "Footprint" "sa800u-baseboard-hw-footprints:SOT-23-3" (id 2) (at 93.98 255.905 0)
      (effects (font (size 1.524 1.524)) (justify left) hide)
    )
    (property "Datasheet" "https://www.onsemi.com/pub/Collateral/BSS84-D.PDF" (id 3) (at 93.98 258.445 0)
      (effects (font (size 1.524 1.524)) (justify left) hide)
    )
    (property "MPN" "BSS84" (id 4) (at 93.98 263.525 0)
      (effects (font (size 1.524 1.524)) (justify left) hide)
    )
    (property "Manufacturer" "ON Semiconductor" (id 5) (at 93.98 278.765 0)
      (effects (font (size 1.524 1.524)) (justify left) hide)
    )
    (property "Author" "Antmicro" (id 6) (at 105.41 233.045 0)
      (effects (font (size 1.27 1.27) (thickness 0.15)) (justify left bottom) hide)
    )
    (property "License" "Apache-2.0" (id 7) (at 105.41 230.505 0)
      (effects (font (size 1.27 1.27) (thickness 0.15)) (justify left bottom) hide)
    )
    (pin "1")
    (pin "2")
    (pin "3")
  )

  (symbol (lib_id "sa800u-baseboard-hw:R_10k_0402") (at 95.25 245.745 180) (unit 1)
    (in_bom yes) (on_board yes) (fields_autoplaced)
    (property "Reference" "R111" (id 0) (at 92.71 238.76 0)
      (effects (font (size 1.524 1.524)))
    )
    (property "Value" "R_10k_0402" (id 1) (at 95.25 241.935 0)
      (effects (font (size 1.524 1.524)) hide)
    )
    (property "Footprint" "sa800u-baseboard-hw-footprints:R_0402_1005Metric" (id 2) (at 90.17 250.825 0)
      (effects (font (size 1.524 1.524)) (justify left) hide)
    )
    (property "Datasheet" "https://www.bourns.com/docs/product-datasheets/cr.pdf" (id 3) (at 95.25 245.745 0)
      (effects (font (size 1.27 1.27)) hide)
    )
    (property "Manufacturer" "Bourns" (id 4) (at 90.17 255.905 0)
      (effects (font (size 1.524 1.524)) (justify left) hide)
    )
    (property "MPN" "CR0402-FX-1002GLF" (id 5) (at 90.17 253.365 0)
      (effects (font (size 1.524 1.524)) (justify left) hide)
    )
    (property "Val" "10k" (id 6) (at 92.71 242.57 0))
    (property "License" "Apache-2.0" (id 7) (at 74.93 220.345 0)
      (effects (font (size 1.27 1.27) (thickness 0.15)) (justify left bottom) hide)
    )
    (property "Author" "Antmicro" (id 8) (at 74.93 217.805 0)
      (effects (font (size 1.27 1.27) (thickness 0.15)) (justify left bottom) hide)
    )
    (property "Tolerance" "1%" (id 9) (at 74.93 235.585 0)
      (effects (font (size 1.27 1.27)) (justify left bottom) hide)
    )
    (pin "1")
    (pin "2")
  )

  (symbol (lib_id "sa800u-baseboard-hw:R_1M_0402") (at 126.238 147.574 270) (unit 1)
    (in_bom yes) (on_board yes) (fields_autoplaced)
    (property "Reference" "R118" (id 0) (at 128.27 148.844 90)
      (effects (font (size 1.524 1.524)) (justify left))
    )
    (property "Value" "R_1M_0402" (id 1) (at 113.538 167.894 0)
      (effects (font (size 1.27 1.27) (thickness 0.15)) (justify left bottom) hide)
    )
    (property "Footprint" "sa800u-baseboard-hw-footprints:R_0402_1005Metric" (id 2) (at 110.998 167.894 0)
      (effects (font (size 1.27 1.27) (thickness 0.15)) (justify left bottom) hide)
    )
    (property "Datasheet" "https://www.bourns.com/docs/product-datasheets/cr.pdf" (id 3) (at 108.458 167.894 0)
      (effects (font (size 1.27 1.27) (thickness 0.15)) (justify left bottom) hide)
    )
    (property "Manufacturer" "Bourns" (id 4) (at 103.378 167.894 0)
      (effects (font (size 1.27 1.27) (thickness 0.15)) (justify left bottom) hide)
    )
    (property "MPN" "CR0402-FX-1004GLF" (id 5) (at 105.918 167.894 0)
      (effects (font (size 1.27 1.27) (thickness 0.15)) (justify left bottom) hide)
    )
    (property "Val" "1M" (id 6) (at 128.27 152.0189 90)
      (effects (font (size 1.27 1.27) (thickness 0.15)) (justify left))
    )
    (property "License" "Apache-2.0" (id 7) (at 100.838 167.894 0)
      (effects (font (size 1.27 1.27) (thickness 0.15)) (justify left bottom) hide)
    )
    (property "Author" "Antmicro" (id 8) (at 98.298 167.894 0)
      (effects (font (size 1.27 1.27) (thickness 0.15)) (justify left bottom) hide)
    )
    (property "Tolerance" "1%" (id 9) (at 116.078 167.894 0)
      (effects (font (size 1.27 1.27)) (justify left bottom) hide)
    )
    (pin "1")
    (pin "2")
  )

  (symbol (lib_id "sa800u-baseboard-hw:R_1M_0402") (at 135.89 147.574 270) (unit 1)
    (in_bom yes) (on_board yes) (fields_autoplaced)
    (property "Reference" "R119" (id 0) (at 138.43 148.844 90)
      (effects (font (size 1.524 1.524)) (justify left))
    )
    (property "Value" "R_1M_0402" (id 1) (at 123.19 167.894 0)
      (effects (font (size 1.27 1.27) (thickness 0.15)) (justify left bottom) hide)
    )
    (property "Footprint" "sa800u-baseboard-hw-footprints:R_0402_1005Metric" (id 2) (at 120.65 167.894 0)
      (effects (font (size 1.27 1.27) (thickness 0.15)) (justify left bottom) hide)
    )
    (property "Datasheet" "https://www.bourns.com/docs/product-datasheets/cr.pdf" (id 3) (at 118.11 167.894 0)
      (effects (font (size 1.27 1.27) (thickness 0.15)) (justify left bottom) hide)
    )
    (property "Manufacturer" "Bourns" (id 4) (at 113.03 167.894 0)
      (effects (font (size 1.27 1.27) (thickness 0.15)) (justify left bottom) hide)
    )
    (property "MPN" "CR0402-FX-1004GLF" (id 5) (at 115.57 167.894 0)
      (effects (font (size 1.27 1.27) (thickness 0.15)) (justify left bottom) hide)
    )
    (property "Val" "1M" (id 6) (at 138.43 152.0189 90)
      (effects (font (size 1.27 1.27) (thickness 0.15)) (justify left))
    )
    (property "License" "Apache-2.0" (id 7) (at 110.49 167.894 0)
      (effects (font (size 1.27 1.27) (thickness 0.15)) (justify left bottom) hide)
    )
    (property "Author" "Antmicro" (id 8) (at 107.95 167.894 0)
      (effects (font (size 1.27 1.27) (thickness 0.15)) (justify left bottom) hide)
    )
    (property "Tolerance" "1%" (id 9) (at 125.73 167.894 0)
      (effects (font (size 1.27 1.27)) (justify left bottom) hide)
    )
    (pin "1")
    (pin "2")
  )

  (symbol (lib_id "sa800u-baseboard-hw:R_1M_0402") (at 145.542 147.574 270) (unit 1)
    (in_bom yes) (on_board yes) (fields_autoplaced)
    (property "Reference" "R120" (id 0) (at 147.32 148.844 90)
      (effects (font (size 1.524 1.524)) (justify left))
    )
    (property "Value" "R_1M_0402" (id 1) (at 132.842 167.894 0)
      (effects (font (size 1.27 1.27) (thickness 0.15)) (justify left bottom) hide)
    )
    (property "Footprint" "sa800u-baseboard-hw-footprints:R_0402_1005Metric" (id 2) (at 130.302 167.894 0)
      (effects (font (size 1.27 1.27) (thickness 0.15)) (justify left bottom) hide)
    )
    (property "Datasheet" "https://www.bourns.com/docs/product-datasheets/cr.pdf" (id 3) (at 127.762 167.894 0)
      (effects (font (size 1.27 1.27) (thickness 0.15)) (justify left bottom) hide)
    )
    (property "Manufacturer" "Bourns" (id 4) (at 122.682 167.894 0)
      (effects (font (size 1.27 1.27) (thickness 0.15)) (justify left bottom) hide)
    )
    (property "MPN" "CR0402-FX-1004GLF" (id 5) (at 125.222 167.894 0)
      (effects (font (size 1.27 1.27) (thickness 0.15)) (justify left bottom) hide)
    )
    (property "Val" "1M" (id 6) (at 147.32 152.0189 90)
      (effects (font (size 1.27 1.27) (thickness 0.15)) (justify left))
    )
    (property "License" "Apache-2.0" (id 7) (at 120.142 167.894 0)
      (effects (font (size 1.27 1.27) (thickness 0.15)) (justify left bottom) hide)
    )
    (property "Author" "Antmicro" (id 8) (at 117.602 167.894 0)
      (effects (font (size 1.27 1.27) (thickness 0.15)) (justify left bottom) hide)
    )
    (property "Tolerance" "1%" (id 9) (at 135.382 167.894 0)
      (effects (font (size 1.27 1.27)) (justify left bottom) hide)
    )
    (pin "1")
    (pin "2")
  )

  (symbol (lib_id "sa800u-baseboard-hw:GND") (at 96.52 259.715 0) (unit 1)
    (in_bom yes) (on_board yes) (fields_autoplaced)
    (property "Reference" "#PWR0202" (id 0) (at 96.52 266.065 0)
      (effects (font (size 1.27 1.27)) hide)
    )
    (property "Value" "GND" (id 1) (at 96.52 264.16 0))
    (property "Footprint" "" (id 2) (at 96.52 259.715 0)
      (effects (font (size 1.27 1.27)) hide)
    )
    (property "Datasheet" "" (id 3) (at 96.52 259.715 0)
      (effects (font (size 1.27 1.27)) hide)
    )
    (property "Author" "Antmicro" (id 4) (at 105.41 267.335 0)
      (effects (font (size 1.27 1.27) (thickness 0.15)) (justify left bottom) hide)
    )
    (property "License" "Apache-2.0" (id 5) (at 105.41 269.875 0)
      (effects (font (size 1.27 1.27) (thickness 0.15)) (justify left bottom) hide)
    )
    (pin "1")
  )

  (symbol (lib_id "sa800u-baseboard-hw:BSS84") (at 128.27 250.825 0) (mirror x) (unit 1)
    (in_bom yes) (on_board yes) (fields_autoplaced)
    (property "Reference" "Q10" (id 0) (at 139.7 252.095 0)
      (effects (font (size 1.524 1.524)) (justify left))
    )
    (property "Value" "BSS84" (id 1) (at 139.7 255.905 0)
      (effects (font (size 1.524 1.524)) (justify left))
    )
    (property "Footprint" "sa800u-baseboard-hw-footprints:SOT-23-3" (id 2) (at 133.35 255.905 0)
      (effects (font (size 1.524 1.524)) (justify left) hide)
    )
    (property "Datasheet" "https://www.onsemi.com/pub/Collateral/BSS84-D.PDF" (id 3) (at 133.35 258.445 0)
      (effects (font (size 1.524 1.524)) (justify left) hide)
    )
    (property "MPN" "BSS84" (id 4) (at 133.35 263.525 0)
      (effects (font (size 1.524 1.524)) (justify left) hide)
    )
    (property "Manufacturer" "ON Semiconductor" (id 5) (at 133.35 278.765 0)
      (effects (font (size 1.524 1.524)) (justify left) hide)
    )
    (property "Author" "Antmicro" (id 6) (at 144.78 233.045 0)
      (effects (font (size 1.27 1.27) (thickness 0.15)) (justify left bottom) hide)
    )
    (property "License" "Apache-2.0" (id 7) (at 144.78 230.505 0)
      (effects (font (size 1.27 1.27) (thickness 0.15)) (justify left bottom) hide)
    )
    (pin "1")
    (pin "2")
    (pin "3")
  )

  (symbol (lib_id "sa800u-baseboard-hw:R_10k_0402") (at 134.62 245.745 180) (unit 1)
    (in_bom yes) (on_board yes) (fields_autoplaced)
    (property "Reference" "R115" (id 0) (at 132.08 238.76 0)
      (effects (font (size 1.524 1.524)))
    )
    (property "Value" "R_10k_0402" (id 1) (at 134.62 241.935 0)
      (effects (font (size 1.524 1.524)) hide)
    )
    (property "Footprint" "sa800u-baseboard-hw-footprints:R_0402_1005Metric" (id 2) (at 129.54 250.825 0)
      (effects (font (size 1.524 1.524)) (justify left) hide)
    )
    (property "Datasheet" "https://www.bourns.com/docs/product-datasheets/cr.pdf" (id 3) (at 134.62 245.745 0)
      (effects (font (size 1.27 1.27)) hide)
    )
    (property "Manufacturer" "Bourns" (id 4) (at 129.54 255.905 0)
      (effects (font (size 1.524 1.524)) (justify left) hide)
    )
    (property "MPN" "CR0402-FX-1002GLF" (id 5) (at 129.54 253.365 0)
      (effects (font (size 1.524 1.524)) (justify left) hide)
    )
    (property "Val" "10k" (id 6) (at 132.08 242.57 0))
    (property "License" "Apache-2.0" (id 7) (at 114.3 220.345 0)
      (effects (font (size 1.27 1.27) (thickness 0.15)) (justify left bottom) hide)
    )
    (property "Author" "Antmicro" (id 8) (at 114.3 217.805 0)
      (effects (font (size 1.27 1.27) (thickness 0.15)) (justify left bottom) hide)
    )
    (property "Tolerance" "1%" (id 9) (at 114.3 235.585 0)
      (effects (font (size 1.27 1.27)) (justify left bottom) hide)
    )
    (pin "1")
    (pin "2")
  )

  (symbol (lib_id "sa800u-baseboard-hw:GND") (at 135.89 259.715 0) (unit 1)
    (in_bom yes) (on_board yes) (fields_autoplaced)
    (property "Reference" "#PWR0205" (id 0) (at 135.89 266.065 0)
      (effects (font (size 1.27 1.27)) hide)
    )
    (property "Value" "GND" (id 1) (at 135.89 264.16 0))
    (property "Footprint" "" (id 2) (at 135.89 259.715 0)
      (effects (font (size 1.27 1.27)) hide)
    )
    (property "Datasheet" "" (id 3) (at 135.89 259.715 0)
      (effects (font (size 1.27 1.27)) hide)
    )
    (property "Author" "Antmicro" (id 4) (at 144.78 267.335 0)
      (effects (font (size 1.27 1.27) (thickness 0.15)) (justify left bottom) hide)
    )
    (property "License" "Apache-2.0" (id 5) (at 144.78 269.875 0)
      (effects (font (size 1.27 1.27) (thickness 0.15)) (justify left bottom) hide)
    )
    (pin "1")
  )

  (symbol (lib_id "sa800u-baseboard-hw:BSS84") (at 169.545 251.46 0) (mirror x) (unit 1)
    (in_bom yes) (on_board yes) (fields_autoplaced)
    (property "Reference" "Q13" (id 0) (at 180.34 252.73 0)
      (effects (font (size 1.524 1.524)) (justify left))
    )
    (property "Value" "BSS84" (id 1) (at 180.34 256.54 0)
      (effects (font (size 1.524 1.524)) (justify left))
    )
    (property "Footprint" "sa800u-baseboard-hw-footprints:SOT-23-3" (id 2) (at 174.625 256.54 0)
      (effects (font (size 1.524 1.524)) (justify left) hide)
    )
    (property "Datasheet" "https://www.onsemi.com/pub/Collateral/BSS84-D.PDF" (id 3) (at 174.625 259.08 0)
      (effects (font (size 1.524 1.524)) (justify left) hide)
    )
    (property "MPN" "BSS84" (id 4) (at 174.625 264.16 0)
      (effects (font (size 1.524 1.524)) (justify left) hide)
    )
    (property "Manufacturer" "ON Semiconductor" (id 5) (at 174.625 279.4 0)
      (effects (font (size 1.524 1.524)) (justify left) hide)
    )
    (property "Author" "Antmicro" (id 6) (at 186.055 233.68 0)
      (effects (font (size 1.27 1.27) (thickness 0.15)) (justify left bottom) hide)
    )
    (property "License" "Apache-2.0" (id 7) (at 186.055 231.14 0)
      (effects (font (size 1.27 1.27) (thickness 0.15)) (justify left bottom) hide)
    )
    (pin "1")
    (pin "2")
    (pin "3")
  )

  (symbol (lib_id "sa800u-baseboard-hw:R_10k_0402") (at 175.895 246.38 180) (unit 1)
    (in_bom yes) (on_board yes) (fields_autoplaced)
    (property "Reference" "R116" (id 0) (at 173.355 240.03 0)
      (effects (font (size 1.524 1.524)))
    )
    (property "Value" "R_10k_0402" (id 1) (at 175.895 242.57 0)
      (effects (font (size 1.524 1.524)) hide)
    )
    (property "Footprint" "sa800u-baseboard-hw-footprints:R_0402_1005Metric" (id 2) (at 170.815 251.46 0)
      (effects (font (size 1.524 1.524)) (justify left) hide)
    )
    (property "Datasheet" "https://www.bourns.com/docs/product-datasheets/cr.pdf" (id 3) (at 175.895 246.38 0)
      (effects (font (size 1.27 1.27)) hide)
    )
    (property "Manufacturer" "Bourns" (id 4) (at 170.815 256.54 0)
      (effects (font (size 1.524 1.524)) (justify left) hide)
    )
    (property "MPN" "CR0402-FX-1002GLF" (id 5) (at 170.815 254 0)
      (effects (font (size 1.524 1.524)) (justify left) hide)
    )
    (property "Val" "10k" (id 6) (at 173.355 242.57 0))
    (property "License" "Apache-2.0" (id 7) (at 155.575 220.98 0)
      (effects (font (size 1.27 1.27) (thickness 0.15)) (justify left bottom) hide)
    )
    (property "Author" "Antmicro" (id 8) (at 155.575 218.44 0)
      (effects (font (size 1.27 1.27) (thickness 0.15)) (justify left bottom) hide)
    )
    (property "Tolerance" "1%" (id 9) (at 155.575 236.22 0)
      (effects (font (size 1.27 1.27)) (justify left bottom) hide)
    )
    (pin "1")
    (pin "2")
  )

  (symbol (lib_id "sa800u-baseboard-hw:GND") (at 177.165 260.35 0) (unit 1)
    (in_bom yes) (on_board yes) (fields_autoplaced)
    (property "Reference" "#PWR0210" (id 0) (at 177.165 266.7 0)
      (effects (font (size 1.27 1.27)) hide)
    )
    (property "Value" "GND" (id 1) (at 177.165 265.43 0))
    (property "Footprint" "" (id 2) (at 177.165 260.35 0)
      (effects (font (size 1.27 1.27)) hide)
    )
    (property "Datasheet" "" (id 3) (at 177.165 260.35 0)
      (effects (font (size 1.27 1.27)) hide)
    )
    (property "Author" "Antmicro" (id 4) (at 186.055 267.97 0)
      (effects (font (size 1.27 1.27) (thickness 0.15)) (justify left bottom) hide)
    )
    (property "License" "Apache-2.0" (id 5) (at 186.055 270.51 0)
      (effects (font (size 1.27 1.27) (thickness 0.15)) (justify left bottom) hide)
    )
    (pin "1")
  )

  (symbol (lib_id "sa800u-baseboard-hw:LED_G_0603_KP-1608ZGC") (at 228.6 87.63 0) (unit 1)
    (in_bom yes) (on_board yes) (fields_autoplaced)
    (property "Reference" "D28" (id 0) (at 232.41 83.82 0)
      (effects (font (size 1.524 1.524)))
    )
    (property "Value" "KP-1608EC" (id 1) (at 227.33 81.7626 0)
      (effects (font (size 1.524 1.524)) hide)
    )
    (property "Footprint" "sa800u-baseboard-hw-footprints:LED_0603_1608Metric_G" (id 2) (at 251.46 97.79 0)
      (effects (font (size 1.27 1.27) (thickness 0.15)) (justify left bottom) hide)
    )
    (property "Datasheet" "https://www.farnell.com/datasheets/2045914.pdf" (id 3) (at 251.46 100.33 0)
      (effects (font (size 1.27 1.27) (thickness 0.15)) (justify left bottom) hide)
    )
    (property "MPN" "KP-1608ZGC" (id 4) (at 251.46 102.87 0)
      (effects (font (size 1.27 1.27) (thickness 0.15)) (justify left bottom) hide)
    )
    (property "Manufacturer" "Kingbright" (id 5) (at 251.46 105.41 0)
      (effects (font (size 1.27 1.27) (thickness 0.15)) (justify left bottom) hide)
    )
    (property "Author" "Antmicro" (id 6) (at 251.46 107.95 0)
      (effects (font (size 1.27 1.27) (thickness 0.15)) (justify left bottom) hide)
    )
    (property "License" "Apache-2.0" (id 7) (at 251.46 110.49 0)
      (effects (font (size 1.27 1.27) (thickness 0.15)) (justify left bottom) hide)
    )
    (pin "1")
    (pin "2")
  )

  (symbol (lib_id "sa800u-baseboard-hw:BSS84") (at 237.49 92.71 0) (mirror x) (unit 1)
    (in_bom yes) (on_board yes) (fields_autoplaced)
    (property "Reference" "Q14" (id 0) (at 248.92 93.98 0)
      (effects (font (size 1.524 1.524)) (justify left))
    )
    (property "Value" "BSS84" (id 1) (at 248.92 97.79 0)
      (effects (font (size 1.524 1.524)) (justify left))
    )
    (property "Footprint" "sa800u-baseboard-hw-footprints:SOT-23-3" (id 2) (at 242.57 97.79 0)
      (effects (font (size 1.524 1.524)) (justify left) hide)
    )
    (property "Datasheet" "https://www.onsemi.com/pub/Collateral/BSS84-D.PDF" (id 3) (at 242.57 100.33 0)
      (effects (font (size 1.524 1.524)) (justify left) hide)
    )
    (property "MPN" "BSS84" (id 4) (at 242.57 105.41 0)
      (effects (font (size 1.524 1.524)) (justify left) hide)
    )
    (property "Manufacturer" "ON Semiconductor" (id 5) (at 242.57 120.65 0)
      (effects (font (size 1.524 1.524)) (justify left) hide)
    )
    (property "Author" "Antmicro" (id 6) (at 254 74.93 0)
      (effects (font (size 1.27 1.27) (thickness 0.15)) (justify left bottom) hide)
    )
    (property "License" "Apache-2.0" (id 7) (at 254 72.39 0)
      (effects (font (size 1.27 1.27) (thickness 0.15)) (justify left bottom) hide)
    )
    (pin "1")
    (pin "2")
    (pin "3")
  )

  (symbol (lib_id "sa800u-baseboard-hw:R_10k_0402") (at 243.332 87.63 180) (unit 1)
    (in_bom yes) (on_board yes) (fields_autoplaced)
    (property "Reference" "R122" (id 0) (at 240.792 81.28 0)
      (effects (font (size 1.524 1.524)))
    )
    (property "Value" "R_10k_0402" (id 1) (at 243.332 83.82 0)
      (effects (font (size 1.524 1.524)) hide)
    )
    (property "Footprint" "sa800u-baseboard-hw-footprints:R_0402_1005Metric" (id 2) (at 238.252 92.71 0)
      (effects (font (size 1.524 1.524)) (justify left) hide)
    )
    (property "Datasheet" "https://www.bourns.com/docs/product-datasheets/cr.pdf" (id 3) (at 243.332 87.63 0)
      (effects (font (size 1.27 1.27)) hide)
    )
    (property "Manufacturer" "Bourns" (id 4) (at 238.252 97.79 0)
      (effects (font (size 1.524 1.524)) (justify left) hide)
    )
    (property "MPN" "CR0402-FX-1002GLF" (id 5) (at 238.252 95.25 0)
      (effects (font (size 1.524 1.524)) (justify left) hide)
    )
    (property "Val" "10k" (id 6) (at 240.792 83.82 0))
    (property "License" "Apache-2.0" (id 7) (at 223.012 62.23 0)
      (effects (font (size 1.27 1.27) (thickness 0.15)) (justify left bottom) hide)
    )
    (property "Author" "Antmicro" (id 8) (at 223.012 59.69 0)
      (effects (font (size 1.27 1.27) (thickness 0.15)) (justify left bottom) hide)
    )
    (property "Tolerance" "1%" (id 9) (at 223.012 77.47 0)
      (effects (font (size 1.27 1.27)) (justify left bottom) hide)
    )
    (pin "1")
    (pin "2")
  )

  (symbol (lib_id "sa800u-baseboard-hw:GND") (at 245.11 101.6 0) (unit 1)
    (in_bom yes) (on_board yes) (fields_autoplaced)
    (property "Reference" "#PWR0215" (id 0) (at 245.11 107.95 0)
      (effects (font (size 1.27 1.27)) hide)
    )
    (property "Value" "GND" (id 1) (at 245.11 106.68 0))
    (property "Footprint" "" (id 2) (at 245.11 101.6 0)
      (effects (font (size 1.27 1.27)) hide)
    )
    (property "Datasheet" "" (id 3) (at 245.11 101.6 0)
      (effects (font (size 1.27 1.27)) hide)
    )
    (property "Author" "Antmicro" (id 4) (at 254 109.22 0)
      (effects (font (size 1.27 1.27) (thickness 0.15)) (justify left bottom) hide)
    )
    (property "License" "Apache-2.0" (id 5) (at 254 111.76 0)
      (effects (font (size 1.27 1.27) (thickness 0.15)) (justify left bottom) hide)
    )
    (pin "1")
  )

  (symbol (lib_id "sa800u-baseboard-hw:SQS401EN-T1_BE3") (at 329.565 48.26 270) (mirror x) (unit 1)
    (in_bom yes) (on_board yes) (fields_autoplaced)
    (property "Reference" "Q16" (id 0) (at 332.105 34.29 90)
      (effects (font (size 1.524 1.524)))
    )
    (property "Value" "SQS401EN-T1_BE3" (id 1) (at 332.105 38.1 90)
      (effects (font (size 1.524 1.524)))
    )
    (property "Footprint" "sa800u-baseboard-hw-footprints:Vishay_PowerPAK_1212-8_Single" (id 2) (at 334.645 43.18 0)
      (effects (font (size 1.524 1.524)) (justify left) hide)
    )
    (property "Datasheet" "https://www.vishay.com/docs/65529/sqs401en.pdf" (id 3) (at 337.185 43.18 0)
      (effects (font (size 1.524 1.524)) (justify left) hide)
    )
    (property "MPN" "SQS401EN-T1_BE3" (id 4) (at 342.265 43.18 0)
      (effects (font (size 1.524 1.524)) (justify left) hide)
    )
    (property "Manufacturer" "Vishay" (id 5) (at 357.505 43.18 0)
      (effects (font (size 1.524 1.524)) (justify left) hide)
    )
    (property "Author" "Antmicro" (id 6) (at 309.245 33.02 0)
      (effects (font (size 1.27 1.27) (thickness 0.15)) (justify left bottom) hide)
    )
    (property "License" "Apache-2.0" (id 7) (at 306.705 33.02 0)
      (effects (font (size 1.27 1.27) (thickness 0.15)) (justify left bottom) hide)
    )
    (pin "1")
    (pin "2")
    (pin "3")
    (pin "4")
    (pin "5")
  )

  (symbol (lib_id "sa800u-baseboard-hw:PWR_FLAG") (at 36.195 54.61 0) (unit 1)
    (in_bom yes) (on_board yes) (fields_autoplaced)
    (property "Reference" "#FLG020" (id 0) (at 36.195 52.705 0)
      (effects (font (size 1.27 1.27)) hide)
    )
    (property "Value" "PWR_FLAG" (id 1) (at 36.195 49.53 0))
    (property "Footprint" "" (id 2) (at 36.195 54.61 0)
      (effects (font (size 1.27 1.27)) hide)
    )
    (property "Datasheet" "~" (id 3) (at 36.195 54.61 0)
      (effects (font (size 1.27 1.27)) hide)
    )
    (pin "1")
  )

  (symbol (lib_id "sa800u-baseboard-hw:GND") (at 320.04 85.09 0) (mirror y) (unit 1)
    (in_bom yes) (on_board yes) (fields_autoplaced)
    (property "Reference" "#PWR0226" (id 0) (at 320.04 91.44 0)
      (effects (font (size 1.27 1.27)) hide)
    )
    (property "Value" "GND" (id 1) (at 320.04 90.17 0))
    (property "Footprint" "" (id 2) (at 320.04 85.09 0)
      (effects (font (size 1.27 1.27)) hide)
    )
    (property "Datasheet" "" (id 3) (at 320.04 85.09 0)
      (effects (font (size 1.27 1.27)) hide)
    )
    (property "Author" "Antmicro" (id 4) (at 311.15 92.71 0)
      (effects (font (size 1.27 1.27) (thickness 0.15)) (justify left bottom) hide)
    )
    (property "License" "Apache-2.0" (id 5) (at 311.15 95.25 0)
      (effects (font (size 1.27 1.27) (thickness 0.15)) (justify left bottom) hide)
    )
    (pin "1")
  )

  (symbol (lib_id "sa800u-baseboard-hw:GND") (at 308.61 85.09 0) (mirror y) (unit 1)
    (in_bom yes) (on_board yes) (fields_autoplaced)
    (property "Reference" "#PWR0225" (id 0) (at 308.61 91.44 0)
      (effects (font (size 1.27 1.27)) hide)
    )
    (property "Value" "GND" (id 1) (at 308.61 90.17 0))
    (property "Footprint" "" (id 2) (at 308.61 85.09 0)
      (effects (font (size 1.27 1.27)) hide)
    )
    (property "Datasheet" "" (id 3) (at 308.61 85.09 0)
      (effects (font (size 1.27 1.27)) hide)
    )
    (property "Author" "Antmicro" (id 4) (at 299.72 92.71 0)
      (effects (font (size 1.27 1.27) (thickness 0.15)) (justify left bottom) hide)
    )
    (property "License" "Apache-2.0" (id 5) (at 299.72 95.25 0)
      (effects (font (size 1.27 1.27) (thickness 0.15)) (justify left bottom) hide)
    )
    (pin "1")
  )

  (symbol (lib_id "sa800u-baseboard-hw:C_10u_25V_0603") (at 69.215 55.88 270) (unit 1)
    (in_bom yes) (on_board yes) (fields_autoplaced)
    (property "Reference" "C121" (id 0) (at 66.294 57.1563 90)
      (effects (font (size 1.524 1.524)) (justify right))
    )
    (property "Value" "C_10u_25V_0603" (id 1) (at 65.405 55.88 0)
      (effects (font (size 1.524 1.524)) hide)
    )
    (property "Footprint" "sa800u-baseboard-hw-footprints:C_0603_1608Metric" (id 2) (at 74.295 60.96 0)
      (effects (font (size 1.524 1.524)) (justify left) hide)
    )
    (property "Datasheet" " " (id 3) (at 69.215 55.88 0)
      (effects (font (size 1.27 1.27)) hide)
    )
    (property "Manufacturer" "TDK" (id 4) (at 79.375 60.96 0)
      (effects (font (size 1.524 1.524)) (justify left) hide)
    )
    (property "MPN" "C1608X5R1E106M080AC" (id 5) (at 76.835 60.96 0)
      (effects (font (size 1.524 1.524)) (justify left) hide)
    )
    (property "Val" "10u/25V" (id 6) (at 66.294 60.3312 90)
      (effects (font (size 1.27 1.27)) (justify right))
    )
    (property "License" "Apache-2.0" (id 7) (at 46.355 76.2 0)
      (effects (font (size 1.27 1.27) (thickness 0.15)) (justify left bottom) hide)
    )
    (property "Author" "Antmicro" (id 8) (at 43.815 76.2 0)
      (effects (font (size 1.27 1.27) (thickness 0.15)) (justify left bottom) hide)
    )
    (property "Voltage" "" (id 9) (at 41.275 76.2 0)
      (effects (font (size 1.27 1.27)) (justify left bottom) hide)
    )
    (property "Dielectric" "" (id 10) (at 38.735 76.2 0)
      (effects (font (size 1.27 1.27)) (justify left bottom) hide)
    )
    (pin "1")
    (pin "2")
  )

  (symbol (lib_id "sa800u-baseboard-hw:C_10u_25V_0603") (at 78.74 55.88 270) (unit 1)
    (in_bom yes) (on_board yes) (fields_autoplaced)
    (property "Reference" "C122" (id 0) (at 82.296 57.1563 90)
      (effects (font (size 1.524 1.524)) (justify left))
    )
    (property "Value" "C_10u_25V_0603" (id 1) (at 74.93 55.88 0)
      (effects (font (size 1.524 1.524)) hide)
    )
    (property "Footprint" "sa800u-baseboard-hw-footprints:C_0603_1608Metric" (id 2) (at 83.82 60.96 0)
      (effects (font (size 1.524 1.524)) (justify left) hide)
    )
    (property "Datasheet" " " (id 3) (at 78.74 55.88 0)
      (effects (font (size 1.27 1.27)) hide)
    )
    (property "Manufacturer" "TDK" (id 4) (at 88.9 60.96 0)
      (effects (font (size 1.524 1.524)) (justify left) hide)
    )
    (property "MPN" "C1608X5R1E106M080AC" (id 5) (at 86.36 60.96 0)
      (effects (font (size 1.524 1.524)) (justify left) hide)
    )
    (property "Val" "10u/25V" (id 6) (at 82.296 60.3312 90)
      (effects (font (size 1.27 1.27)) (justify left))
    )
    (property "License" "Apache-2.0" (id 7) (at 55.88 76.2 0)
      (effects (font (size 1.27 1.27) (thickness 0.15)) (justify left bottom) hide)
    )
    (property "Author" "Antmicro" (id 8) (at 53.34 76.2 0)
      (effects (font (size 1.27 1.27) (thickness 0.15)) (justify left bottom) hide)
    )
    (property "Voltage" "" (id 9) (at 50.8 76.2 0)
      (effects (font (size 1.27 1.27)) (justify left bottom) hide)
    )
    (property "Dielectric" "" (id 10) (at 48.26 76.2 0)
      (effects (font (size 1.27 1.27)) (justify left bottom) hide)
    )
    (pin "1")
    (pin "2")
  )

  (symbol (lib_id "sa800u-baseboard-hw:GND") (at 69.215 60.96 0) (unit 1)
    (in_bom yes) (on_board yes) (fields_autoplaced)
    (property "Reference" "#PWR0201" (id 0) (at 69.215 67.31 0)
      (effects (font (size 1.27 1.27)) hide)
    )
    (property "Value" "GND" (id 1) (at 69.215 66.04 0))
    (property "Footprint" "" (id 2) (at 69.215 60.96 0)
      (effects (font (size 1.27 1.27)) hide)
    )
    (property "Datasheet" "" (id 3) (at 69.215 60.96 0)
      (effects (font (size 1.27 1.27)) hide)
    )
    (property "Author" "Antmicro" (id 4) (at 78.105 68.58 0)
      (effects (font (size 1.27 1.27) (thickness 0.15)) (justify left bottom) hide)
    )
    (property "License" "Apache-2.0" (id 5) (at 78.105 71.12 0)
      (effects (font (size 1.27 1.27) (thickness 0.15)) (justify left bottom) hide)
    )
    (pin "1")
  )

  (symbol (lib_id "sa800u-baseboard-hw:GND") (at 78.74 60.96 0) (unit 1)
    (in_bom yes) (on_board yes) (fields_autoplaced)
    (property "Reference" "#PWR0203" (id 0) (at 78.74 67.31 0)
      (effects (font (size 1.27 1.27)) hide)
    )
    (property "Value" "GND" (id 1) (at 78.74 66.04 0))
    (property "Footprint" "" (id 2) (at 78.74 60.96 0)
      (effects (font (size 1.27 1.27)) hide)
    )
    (property "Datasheet" "" (id 3) (at 78.74 60.96 0)
      (effects (font (size 1.27 1.27)) hide)
    )
    (property "Author" "Antmicro" (id 4) (at 87.63 68.58 0)
      (effects (font (size 1.27 1.27) (thickness 0.15)) (justify left bottom) hide)
    )
    (property "License" "Apache-2.0" (id 5) (at 87.63 71.12 0)
      (effects (font (size 1.27 1.27) (thickness 0.15)) (justify left bottom) hide)
    )
    (pin "1")
  )

  (symbol (lib_id "sa800u-baseboard-hw:C_10u_25V_0603") (at 159.385 58.42 270) (unit 1)
    (in_bom yes) (on_board yes) (fields_autoplaced)
    (property "Reference" "C126" (id 0) (at 162.56 59.6963 90)
      (effects (font (size 1.524 1.524)) (justify left))
    )
    (property "Value" "C_10u_25V_0603" (id 1) (at 155.575 58.42 0)
      (effects (font (size 1.524 1.524)) hide)
    )
    (property "Footprint" "sa800u-baseboard-hw-footprints:C_0603_1608Metric" (id 2) (at 164.465 63.5 0)
      (effects (font (size 1.524 1.524)) (justify left) hide)
    )
    (property "Datasheet" " " (id 3) (at 159.385 58.42 0)
      (effects (font (size 1.27 1.27)) hide)
    )
    (property "Manufacturer" "TDK" (id 4) (at 169.545 63.5 0)
      (effects (font (size 1.524 1.524)) (justify left) hide)
    )
    (property "MPN" "C1608X5R1E106M080AC" (id 5) (at 167.005 63.5 0)
      (effects (font (size 1.524 1.524)) (justify left) hide)
    )
    (property "Val" "10u/25V" (id 6) (at 162.56 62.8712 90)
      (effects (font (size 1.27 1.27)) (justify left))
    )
    (property "License" "Apache-2.0" (id 7) (at 136.525 78.74 0)
      (effects (font (size 1.27 1.27) (thickness 0.15)) (justify left bottom) hide)
    )
    (property "Author" "Antmicro" (id 8) (at 133.985 78.74 0)
      (effects (font (size 1.27 1.27) (thickness 0.15)) (justify left bottom) hide)
    )
    (property "Voltage" "" (id 9) (at 131.445 78.74 0)
      (effects (font (size 1.27 1.27)) (justify left bottom) hide)
    )
    (property "Dielectric" "" (id 10) (at 128.905 78.74 0)
      (effects (font (size 1.27 1.27)) (justify left bottom) hide)
    )
    (pin "1")
    (pin "2")
  )

  (symbol (lib_id "sa800u-baseboard-hw:C_10u_25V_0603") (at 173.355 58.42 270) (unit 1)
    (in_bom yes) (on_board yes) (fields_autoplaced)
    (property "Reference" "C127" (id 0) (at 176.53 59.6963 90)
      (effects (font (size 1.524 1.524)) (justify left))
    )
    (property "Value" "C_10u_25V_0603" (id 1) (at 169.545 58.42 0)
      (effects (font (size 1.524 1.524)) hide)
    )
    (property "Footprint" "sa800u-baseboard-hw-footprints:C_0603_1608Metric" (id 2) (at 178.435 63.5 0)
      (effects (font (size 1.524 1.524)) (justify left) hide)
    )
    (property "Datasheet" " " (id 3) (at 173.355 58.42 0)
      (effects (font (size 1.27 1.27)) hide)
    )
    (property "Manufacturer" "TDK" (id 4) (at 183.515 63.5 0)
      (effects (font (size 1.524 1.524)) (justify left) hide)
    )
    (property "MPN" "C1608X5R1E106M080AC" (id 5) (at 180.975 63.5 0)
      (effects (font (size 1.524 1.524)) (justify left) hide)
    )
    (property "Val" "10u/25V" (id 6) (at 176.53 62.8712 90)
      (effects (font (size 1.27 1.27)) (justify left))
    )
    (property "License" "Apache-2.0" (id 7) (at 150.495 78.74 0)
      (effects (font (size 1.27 1.27) (thickness 0.15)) (justify left bottom) hide)
    )
    (property "Author" "Antmicro" (id 8) (at 147.955 78.74 0)
      (effects (font (size 1.27 1.27) (thickness 0.15)) (justify left bottom) hide)
    )
    (property "Voltage" "" (id 9) (at 145.415 78.74 0)
      (effects (font (size 1.27 1.27)) (justify left bottom) hide)
    )
    (property "Dielectric" "" (id 10) (at 142.875 78.74 0)
      (effects (font (size 1.27 1.27)) (justify left bottom) hide)
    )
    (pin "1")
    (pin "2")
  )

  (symbol (lib_id "sa800u-baseboard-hw:GND") (at 173.355 63.5 0) (unit 1)
    (in_bom yes) (on_board yes) (fields_autoplaced)
    (property "Reference" "#PWR0212" (id 0) (at 173.355 69.85 0)
      (effects (font (size 1.27 1.27)) hide)
    )
    (property "Value" "GND" (id 1) (at 173.355 68.58 0))
    (property "Footprint" "" (id 2) (at 173.355 63.5 0)
      (effects (font (size 1.27 1.27)) hide)
    )
    (property "Datasheet" "" (id 3) (at 173.355 63.5 0)
      (effects (font (size 1.27 1.27)) hide)
    )
    (property "Author" "Antmicro" (id 4) (at 182.245 71.12 0)
      (effects (font (size 1.27 1.27) (thickness 0.15)) (justify left bottom) hide)
    )
    (property "License" "Apache-2.0" (id 5) (at 182.245 73.66 0)
      (effects (font (size 1.27 1.27) (thickness 0.15)) (justify left bottom) hide)
    )
    (pin "1")
  )

  (symbol (lib_id "sa800u-baseboard-hw:GND") (at 159.385 63.5 0) (unit 1)
    (in_bom yes) (on_board yes) (fields_autoplaced)
    (property "Reference" "#PWR0211" (id 0) (at 159.385 69.85 0)
      (effects (font (size 1.27 1.27)) hide)
    )
    (property "Value" "GND" (id 1) (at 159.385 68.58 0))
    (property "Footprint" "" (id 2) (at 159.385 63.5 0)
      (effects (font (size 1.27 1.27)) hide)
    )
    (property "Datasheet" "" (id 3) (at 159.385 63.5 0)
      (effects (font (size 1.27 1.27)) hide)
    )
    (property "Author" "Antmicro" (id 4) (at 168.275 71.12 0)
      (effects (font (size 1.27 1.27) (thickness 0.15)) (justify left bottom) hide)
    )
    (property "License" "Apache-2.0" (id 5) (at 168.275 73.66 0)
      (effects (font (size 1.27 1.27) (thickness 0.15)) (justify left bottom) hide)
    )
    (pin "1")
  )

  (symbol (lib_id "sa800u-baseboard-hw:TP_0.75mm_SMD") (at 400.685 247.015 90) (unit 1)
    (in_bom yes) (on_board yes) (fields_autoplaced)
    (property "Reference" "TP76" (id 0) (at 402.717 243.8399 90)
      (effects (font (size 1.27 1.27)) (justify right))
    )
    (property "Value" "TP_0.75mm_SMD" (id 1) (at 400.685 247.015 0)
      (effects (font (size 1.27 1.27)) hide)
    )
    (property "Footprint" "sa800u-baseboard-hw-footprints:TP_SMD_0.75mm" (id 2) (at 400.685 247.015 0)
      (effects (font (size 1.27 1.27)) hide)
    )
    (property "Datasheet" "" (id 3) (at 400.685 247.015 0)
      (effects (font (size 1.27 1.27)) hide)
    )
    (property "MPN" "" (id 4) (at 415.925 229.235 0)
      (effects (font (size 1.27 1.27) (thickness 0.15)) (justify left bottom) hide)
    )
    (property "Manufacturer" "" (id 5) (at 418.465 229.235 0)
      (effects (font (size 1.27 1.27) (thickness 0.15)) (justify left bottom) hide)
    )
    (property "Author" "Antmicro" (id 6) (at 421.005 229.235 0)
      (effects (font (size 1.27 1.27) (thickness 0.15)) (justify left bottom) hide)
    )
    (property "License" "Apache-2.0" (id 7) (at 423.545 229.235 0)
      (effects (font (size 1.27 1.27) (thickness 0.15)) (justify left bottom) hide)
    )
    (pin "1")
  )

  (symbol (lib_id "sa800u-baseboard-hw:GND") (at 400.685 247.015 0) (unit 1)
    (in_bom yes) (on_board yes) (fields_autoplaced)
    (property "Reference" "#PWR0241" (id 0) (at 400.685 253.365 0)
      (effects (font (size 1.27 1.27)) hide)
    )
    (property "Value" "GND" (id 1) (at 400.685 251.46 0))
    (property "Footprint" "" (id 2) (at 400.685 247.015 0)
      (effects (font (size 1.27 1.27)) hide)
    )
    (property "Datasheet" "" (id 3) (at 400.685 247.015 0)
      (effects (font (size 1.27 1.27)) hide)
    )
    (property "Author" "Antmicro" (id 4) (at 409.575 254.635 0)
      (effects (font (size 1.27 1.27) (thickness 0.15)) (justify left bottom) hide)
    )
    (property "License" "Apache-2.0" (id 5) (at 409.575 257.175 0)
      (effects (font (size 1.27 1.27) (thickness 0.15)) (justify left bottom) hide)
    )
    (pin "1")
  )

  (symbol (lib_id "sa800u-baseboard-hw:TP_0.75mm_SMD") (at 348.869 220.472 90) (unit 1)
    (in_bom yes) (on_board yes) (fields_autoplaced)
    (property "Reference" "TP72" (id 0) (at 350.647 217.2969 90)
      (effects (font (size 1.27 1.27)) (justify right))
    )
    (property "Value" "TP_0.75mm_SMD" (id 1) (at 348.869 220.472 0)
      (effects (font (size 1.27 1.27)) hide)
    )
    (property "Footprint" "sa800u-baseboard-hw-footprints:TP_SMD_0.75mm" (id 2) (at 348.869 220.472 0)
      (effects (font (size 1.27 1.27)) hide)
    )
    (property "Datasheet" "" (id 3) (at 348.869 220.472 0)
      (effects (font (size 1.27 1.27)) hide)
    )
    (property "MPN" "" (id 4) (at 364.109 202.692 0)
      (effects (font (size 1.27 1.27) (thickness 0.15)) (justify left bottom) hide)
    )
    (property "Manufacturer" "" (id 5) (at 366.649 202.692 0)
      (effects (font (size 1.27 1.27) (thickness 0.15)) (justify left bottom) hide)
    )
    (property "Author" "Antmicro" (id 6) (at 369.189 202.692 0)
      (effects (font (size 1.27 1.27) (thickness 0.15)) (justify left bottom) hide)
    )
    (property "License" "Apache-2.0" (id 7) (at 371.729 202.692 0)
      (effects (font (size 1.27 1.27) (thickness 0.15)) (justify left bottom) hide)
    )
    (pin "1")
  )

  (symbol (lib_id "sa800u-baseboard-hw:TP_0.75mm_SMD") (at 348.996 185.674 90) (unit 1)
    (in_bom yes) (on_board yes) (fields_autoplaced)
    (property "Reference" "TP71" (id 0) (at 350.774 182.4989 90)
      (effects (font (size 1.27 1.27)) (justify right))
    )
    (property "Value" "TP_0.75mm_SMD" (id 1) (at 348.996 185.674 0)
      (effects (font (size 1.27 1.27)) hide)
    )
    (property "Footprint" "sa800u-baseboard-hw-footprints:TP_SMD_0.75mm" (id 2) (at 348.996 185.674 0)
      (effects (font (size 1.27 1.27)) hide)
    )
    (property "Datasheet" "" (id 3) (at 348.996 185.674 0)
      (effects (font (size 1.27 1.27)) hide)
    )
    (property "MPN" "" (id 4) (at 364.236 167.894 0)
      (effects (font (size 1.27 1.27) (thickness 0.15)) (justify left bottom) hide)
    )
    (property "Manufacturer" "" (id 5) (at 366.776 167.894 0)
      (effects (font (size 1.27 1.27) (thickness 0.15)) (justify left bottom) hide)
    )
    (property "Author" "Antmicro" (id 6) (at 369.316 167.894 0)
      (effects (font (size 1.27 1.27) (thickness 0.15)) (justify left bottom) hide)
    )
    (property "License" "Apache-2.0" (id 7) (at 371.856 167.894 0)
      (effects (font (size 1.27 1.27) (thickness 0.15)) (justify left bottom) hide)
    )
    (pin "1")
  )

  (symbol (lib_id "sa800u-baseboard-hw:TP_0.75mm_SMD") (at 348.869 150.495 90) (unit 1)
    (in_bom yes) (on_board yes) (fields_autoplaced)
    (property "Reference" "TP70" (id 0) (at 350.774 147.3199 90)
      (effects (font (size 1.27 1.27)) (justify right))
    )
    (property "Value" "TP_0.75mm_SMD" (id 1) (at 348.869 150.495 0)
      (effects (font (size 1.27 1.27)) hide)
    )
    (property "Footprint" "sa800u-baseboard-hw-footprints:TP_SMD_0.75mm" (id 2) (at 348.869 150.495 0)
      (effects (font (size 1.27 1.27)) hide)
    )
    (property "Datasheet" "" (id 3) (at 348.869 150.495 0)
      (effects (font (size 1.27 1.27)) hide)
    )
    (property "MPN" "" (id 4) (at 364.109 132.715 0)
      (effects (font (size 1.27 1.27) (thickness 0.15)) (justify left bottom) hide)
    )
    (property "Manufacturer" "" (id 5) (at 366.649 132.715 0)
      (effects (font (size 1.27 1.27) (thickness 0.15)) (justify left bottom) hide)
    )
    (property "Author" "Antmicro" (id 6) (at 369.189 132.715 0)
      (effects (font (size 1.27 1.27) (thickness 0.15)) (justify left bottom) hide)
    )
    (property "License" "Apache-2.0" (id 7) (at 371.729 132.715 0)
      (effects (font (size 1.27 1.27) (thickness 0.15)) (justify left bottom) hide)
    )
    (pin "1")
  )

  (symbol (lib_id "sa800u-baseboard-hw:TP_0.75mm_SMD") (at 282.067 220.853 90) (unit 1)
    (in_bom yes) (on_board yes) (fields_autoplaced)
    (property "Reference" "TP63" (id 0) (at 284.226 217.6779 90)
      (effects (font (size 1.27 1.27)) (justify right))
    )
    (property "Value" "TP_0.75mm_SMD" (id 1) (at 282.067 220.853 0)
      (effects (font (size 1.27 1.27)) hide)
    )
    (property "Footprint" "sa800u-baseboard-hw-footprints:TP_SMD_0.75mm" (id 2) (at 282.067 220.853 0)
      (effects (font (size 1.27 1.27)) hide)
    )
    (property "Datasheet" "" (id 3) (at 282.067 220.853 0)
      (effects (font (size 1.27 1.27)) hide)
    )
    (property "MPN" "" (id 4) (at 297.307 203.073 0)
      (effects (font (size 1.27 1.27) (thickness 0.15)) (justify left bottom) hide)
    )
    (property "Manufacturer" "" (id 5) (at 299.847 203.073 0)
      (effects (font (size 1.27 1.27) (thickness 0.15)) (justify left bottom) hide)
    )
    (property "Author" "Antmicro" (id 6) (at 302.387 203.073 0)
      (effects (font (size 1.27 1.27) (thickness 0.15)) (justify left bottom) hide)
    )
    (property "License" "Apache-2.0" (id 7) (at 304.927 203.073 0)
      (effects (font (size 1.27 1.27) (thickness 0.15)) (justify left bottom) hide)
    )
    (pin "1")
  )

  (symbol (lib_id "sa800u-baseboard-hw:TP_0.75mm_SMD") (at 282.194 185.547 90) (unit 1)
    (in_bom yes) (on_board yes) (fields_autoplaced)
    (property "Reference" "TP62" (id 0) (at 284.353 182.3719 90)
      (effects (font (size 1.27 1.27)) (justify right))
    )
    (property "Value" "TP_0.75mm_SMD" (id 1) (at 282.194 185.547 0)
      (effects (font (size 1.27 1.27)) hide)
    )
    (property "Footprint" "sa800u-baseboard-hw-footprints:TP_SMD_0.75mm" (id 2) (at 282.194 185.547 0)
      (effects (font (size 1.27 1.27)) hide)
    )
    (property "Datasheet" "" (id 3) (at 282.194 185.547 0)
      (effects (font (size 1.27 1.27)) hide)
    )
    (property "MPN" "" (id 4) (at 297.434 167.767 0)
      (effects (font (size 1.27 1.27) (thickness 0.15)) (justify left bottom) hide)
    )
    (property "Manufacturer" "" (id 5) (at 299.974 167.767 0)
      (effects (font (size 1.27 1.27) (thickness 0.15)) (justify left bottom) hide)
    )
    (property "Author" "Antmicro" (id 6) (at 302.514 167.767 0)
      (effects (font (size 1.27 1.27) (thickness 0.15)) (justify left bottom) hide)
    )
    (property "License" "Apache-2.0" (id 7) (at 305.054 167.767 0)
      (effects (font (size 1.27 1.27) (thickness 0.15)) (justify left bottom) hide)
    )
    (pin "1")
  )

  (symbol (lib_id "sa800u-baseboard-hw:TP_0.75mm_SMD") (at 282.575 150.876 90) (unit 1)
    (in_bom yes) (on_board yes) (fields_autoplaced)
    (property "Reference" "TP61" (id 0) (at 284.226 147.7009 90)
      (effects (font (size 1.27 1.27)) (justify right))
    )
    (property "Value" "TP_0.75mm_SMD" (id 1) (at 282.575 150.876 0)
      (effects (font (size 1.27 1.27)) hide)
    )
    (property "Footprint" "sa800u-baseboard-hw-footprints:TP_SMD_0.75mm" (id 2) (at 282.575 150.876 0)
      (effects (font (size 1.27 1.27)) hide)
    )
    (property "Datasheet" "" (id 3) (at 282.575 150.876 0)
      (effects (font (size 1.27 1.27)) hide)
    )
    (property "MPN" "" (id 4) (at 297.815 133.096 0)
      (effects (font (size 1.27 1.27) (thickness 0.15)) (justify left bottom) hide)
    )
    (property "Manufacturer" "" (id 5) (at 300.355 133.096 0)
      (effects (font (size 1.27 1.27) (thickness 0.15)) (justify left bottom) hide)
    )
    (property "Author" "Antmicro" (id 6) (at 302.895 133.096 0)
      (effects (font (size 1.27 1.27) (thickness 0.15)) (justify left bottom) hide)
    )
    (property "License" "Apache-2.0" (id 7) (at 305.435 133.096 0)
      (effects (font (size 1.27 1.27) (thickness 0.15)) (justify left bottom) hide)
    )
    (pin "1")
  )

  (symbol (lib_id "sa800u-baseboard-hw:TP_0.75mm_SMD") (at 396.621 99.314 90) (unit 1)
    (in_bom yes) (on_board yes) (fields_autoplaced)
    (property "Reference" "TP77" (id 0) (at 398.78 96.1389 90)
      (effects (font (size 1.27 1.27)) (justify right))
    )
    (property "Value" "TP_0.75mm_SMD" (id 1) (at 396.621 99.314 0)
      (effects (font (size 1.27 1.27)) hide)
    )
    (property "Footprint" "sa800u-baseboard-hw-footprints:TP_SMD_0.75mm" (id 2) (at 396.621 99.314 0)
      (effects (font (size 1.27 1.27)) hide)
    )
    (property "Datasheet" "" (id 3) (at 396.621 99.314 0)
      (effects (font (size 1.27 1.27)) hide)
    )
    (property "MPN" "" (id 4) (at 411.861 81.534 0)
      (effects (font (size 1.27 1.27) (thickness 0.15)) (justify left bottom) hide)
    )
    (property "Manufacturer" "" (id 5) (at 414.401 81.534 0)
      (effects (font (size 1.27 1.27) (thickness 0.15)) (justify left bottom) hide)
    )
    (property "Author" "Antmicro" (id 6) (at 416.941 81.534 0)
      (effects (font (size 1.27 1.27) (thickness 0.15)) (justify left bottom) hide)
    )
    (property "License" "Apache-2.0" (id 7) (at 419.481 81.534 0)
      (effects (font (size 1.27 1.27) (thickness 0.15)) (justify left bottom) hide)
    )
    (pin "1")
  )

  (symbol (lib_id "sa800u-baseboard-hw:GND") (at 396.621 99.314 0) (unit 1)
    (in_bom yes) (on_board yes) (fields_autoplaced)
    (property "Reference" "#PWR0242" (id 0) (at 396.621 105.664 0)
      (effects (font (size 1.27 1.27)) hide)
    )
    (property "Value" "GND" (id 1) (at 396.621 103.759 0))
    (property "Footprint" "" (id 2) (at 396.621 99.314 0)
      (effects (font (size 1.27 1.27)) hide)
    )
    (property "Datasheet" "" (id 3) (at 396.621 99.314 0)
      (effects (font (size 1.27 1.27)) hide)
    )
    (property "Author" "Antmicro" (id 4) (at 405.511 106.934 0)
      (effects (font (size 1.27 1.27) (thickness 0.15)) (justify left bottom) hide)
    )
    (property "License" "Apache-2.0" (id 5) (at 405.511 109.474 0)
      (effects (font (size 1.27 1.27) (thickness 0.15)) (justify left bottom) hide)
    )
    (pin "1")
  )

  (symbol (lib_id "sa800u-baseboard-hw:TP_0.75mm_SMD") (at 196.215 275.59 90) (unit 1)
    (in_bom yes) (on_board yes) (fields_autoplaced)
    (property "Reference" "TP58" (id 0) (at 198.12 272.4149 90)
      (effects (font (size 1.27 1.27)) (justify right))
    )
    (property "Value" "TP_0.75mm_SMD" (id 1) (at 196.215 275.59 0)
      (effects (font (size 1.27 1.27)) hide)
    )
    (property "Footprint" "sa800u-baseboard-hw-footprints:TP_SMD_0.75mm" (id 2) (at 196.215 275.59 0)
      (effects (font (size 1.27 1.27)) hide)
    )
    (property "Datasheet" "" (id 3) (at 196.215 275.59 0)
      (effects (font (size 1.27 1.27)) hide)
    )
    (property "MPN" "" (id 4) (at 211.455 257.81 0)
      (effects (font (size 1.27 1.27) (thickness 0.15)) (justify left bottom) hide)
    )
    (property "Manufacturer" "" (id 5) (at 213.995 257.81 0)
      (effects (font (size 1.27 1.27) (thickness 0.15)) (justify left bottom) hide)
    )
    (property "Author" "Antmicro" (id 6) (at 216.535 257.81 0)
      (effects (font (size 1.27 1.27) (thickness 0.15)) (justify left bottom) hide)
    )
    (property "License" "Apache-2.0" (id 7) (at 219.075 257.81 0)
      (effects (font (size 1.27 1.27) (thickness 0.15)) (justify left bottom) hide)
    )
    (pin "1")
  )

  (symbol (lib_id "sa800u-baseboard-hw:GND") (at 196.215 275.59 0) (unit 1)
    (in_bom yes) (on_board yes) (fields_autoplaced)
    (property "Reference" "#PWR0214" (id 0) (at 196.215 281.94 0)
      (effects (font (size 1.27 1.27)) hide)
    )
    (property "Value" "GND" (id 1) (at 196.215 280.67 0))
    (property "Footprint" "" (id 2) (at 196.215 275.59 0)
      (effects (font (size 1.27 1.27)) hide)
    )
    (property "Datasheet" "" (id 3) (at 196.215 275.59 0)
      (effects (font (size 1.27 1.27)) hide)
    )
    (property "Author" "Antmicro" (id 4) (at 205.105 283.21 0)
      (effects (font (size 1.27 1.27) (thickness 0.15)) (justify left bottom) hide)
    )
    (property "License" "Apache-2.0" (id 5) (at 205.105 285.75 0)
      (effects (font (size 1.27 1.27) (thickness 0.15)) (justify left bottom) hide)
    )
    (pin "1")
  )

  (symbol (lib_id "sa800u-baseboard-hw:TP_0.75mm_SMD") (at 155.067 53.086 90) (unit 1)
    (in_bom yes) (on_board yes) (fields_autoplaced)
    (property "Reference" "TP56" (id 0) (at 157.353 49.9109 90)
      (effects (font (size 1.27 1.27)) (justify right))
    )
    (property "Value" "TP_0.75mm_SMD" (id 1) (at 155.067 53.086 0)
      (effects (font (size 1.27 1.27)) hide)
    )
    (property "Footprint" "sa800u-baseboard-hw-footprints:TP_SMD_0.75mm" (id 2) (at 155.067 53.086 0)
      (effects (font (size 1.27 1.27)) hide)
    )
    (property "Datasheet" "" (id 3) (at 155.067 53.086 0)
      (effects (font (size 1.27 1.27)) hide)
    )
    (property "MPN" "" (id 4) (at 170.307 35.306 0)
      (effects (font (size 1.27 1.27) (thickness 0.15)) (justify left bottom) hide)
    )
    (property "Manufacturer" "" (id 5) (at 172.847 35.306 0)
      (effects (font (size 1.27 1.27) (thickness 0.15)) (justify left bottom) hide)
    )
    (property "Author" "Antmicro" (id 6) (at 175.387 35.306 0)
      (effects (font (size 1.27 1.27) (thickness 0.15)) (justify left bottom) hide)
    )
    (property "License" "Apache-2.0" (id 7) (at 177.927 35.306 0)
      (effects (font (size 1.27 1.27) (thickness 0.15)) (justify left bottom) hide)
    )
    (pin "1")
  )

  (symbol (lib_id "sa800u-baseboard-hw:TP_0.75mm_SMD") (at 107.95 154.94 90) (unit 1)
    (in_bom yes) (on_board yes)
    (property "Reference" "TP54" (id 0) (at 105.791 149.987 90)
      (effects (font (size 1.27 1.27)) (justify right))
    )
    (property "Value" "TP_0.75mm_SMD" (id 1) (at 110.49 154.94 0)
      (effects (font (size 1.27 1.27)) hide)
    )
    (property "Footprint" "sa800u-baseboard-hw-footprints:TP_SMD_0.75mm" (id 2) (at 102.87 149.86 0)
      (effects (font (size 1.524 1.524)) (justify left) hide)
    )
    (property "Datasheet" "" (id 3) (at 100.33 149.86 0)
      (effects (font (size 1.524 1.524)) (justify left) hide)
    )
    (property "MPN" "" (id 4) (at 123.19 137.16 0)
      (effects (font (size 1.27 1.27) (thickness 0.15)) (justify left bottom) hide)
    )
    (property "Manufacturer" "" (id 5) (at 125.73 137.16 0)
      (effects (font (size 1.27 1.27) (thickness 0.15)) (justify left bottom) hide)
    )
    (property "Author" "Antmicro" (id 6) (at 128.27 137.16 0)
      (effects (font (size 1.27 1.27) (thickness 0.15)) (justify left bottom) hide)
    )
    (property "License" "Apache-2.0" (id 7) (at 130.81 137.16 0)
      (effects (font (size 1.27 1.27) (thickness 0.15)) (justify left bottom) hide)
    )
    (pin "1")
  )

  (symbol (lib_id "sa800u-baseboard-hw:TP_0.75mm_SMD") (at 115.57 154.94 90) (unit 1)
    (in_bom yes) (on_board yes)
    (property "Reference" "TP55" (id 0) (at 113.03 149.987 90)
      (effects (font (size 1.27 1.27)) (justify right))
    )
    (property "Value" "TP_0.75mm_SMD" (id 1) (at 118.11 154.94 0)
      (effects (font (size 1.27 1.27)) hide)
    )
    (property "Footprint" "sa800u-baseboard-hw-footprints:TP_SMD_0.75mm" (id 2) (at 110.49 149.86 0)
      (effects (font (size 1.524 1.524)) (justify left) hide)
    )
    (property "Datasheet" "" (id 3) (at 107.95 149.86 0)
      (effects (font (size 1.524 1.524)) (justify left) hide)
    )
    (property "MPN" "" (id 4) (at 130.81 137.16 0)
      (effects (font (size 1.27 1.27) (thickness 0.15)) (justify left bottom) hide)
    )
    (property "Manufacturer" "" (id 5) (at 133.35 137.16 0)
      (effects (font (size 1.27 1.27) (thickness 0.15)) (justify left bottom) hide)
    )
    (property "Author" "Antmicro" (id 6) (at 135.89 137.16 0)
      (effects (font (size 1.27 1.27) (thickness 0.15)) (justify left bottom) hide)
    )
    (property "License" "Apache-2.0" (id 7) (at 138.43 137.16 0)
      (effects (font (size 1.27 1.27) (thickness 0.15)) (justify left bottom) hide)
    )
    (pin "1")
  )

  (symbol (lib_id "sa800u-baseboard-hw:TP_0.75mm_SMD") (at 123.19 154.94 90) (unit 1)
    (in_bom yes) (on_board yes)
    (property "Reference" "TP57" (id 0) (at 124.968 149.987 90)
      (effects (font (size 1.27 1.27)) (justify left))
    )
    (property "Value" "TP_0.75mm_SMD" (id 1) (at 125.73 154.94 0)
      (effects (font (size 1.27 1.27)) hide)
    )
    (property "Footprint" "sa800u-baseboard-hw-footprints:TP_SMD_0.75mm" (id 2) (at 118.11 149.86 0)
      (effects (font (size 1.524 1.524)) (justify left) hide)
    )
    (property "Datasheet" "" (id 3) (at 115.57 149.86 0)
      (effects (font (size 1.524 1.524)) (justify left) hide)
    )
    (property "MPN" "" (id 4) (at 138.43 137.16 0)
      (effects (font (size 1.27 1.27) (thickness 0.15)) (justify left bottom) hide)
    )
    (property "Manufacturer" "" (id 5) (at 140.97 137.16 0)
      (effects (font (size 1.27 1.27) (thickness 0.15)) (justify left bottom) hide)
    )
    (property "Author" "Antmicro" (id 6) (at 143.51 137.16 0)
      (effects (font (size 1.27 1.27) (thickness 0.15)) (justify left bottom) hide)
    )
    (property "License" "Apache-2.0" (id 7) (at 146.05 137.16 0)
      (effects (font (size 1.27 1.27) (thickness 0.15)) (justify left bottom) hide)
    )
    (pin "1")
  )

  (symbol (lib_id "sa800u-baseboard-hw:TP_0.75mm_SMD") (at 398.145 201.295 90) (unit 1)
    (in_bom yes) (on_board yes) (fields_autoplaced)
    (property "Reference" "TP75" (id 0) (at 400.177 198.1199 90)
      (effects (font (size 1.27 1.27)) (justify right))
    )
    (property "Value" "TP_0.75mm_SMD" (id 1) (at 398.145 201.295 0)
      (effects (font (size 1.27 1.27)) hide)
    )
    (property "Footprint" "sa800u-baseboard-hw-footprints:TP_SMD_0.75mm" (id 2) (at 398.145 201.295 0)
      (effects (font (size 1.27 1.27)) hide)
    )
    (property "Datasheet" "" (id 3) (at 398.145 201.295 0)
      (effects (font (size 1.27 1.27)) hide)
    )
    (property "MPN" "" (id 4) (at 413.385 183.515 0)
      (effects (font (size 1.27 1.27) (thickness 0.15)) (justify left bottom) hide)
    )
    (property "Manufacturer" "" (id 5) (at 415.925 183.515 0)
      (effects (font (size 1.27 1.27) (thickness 0.15)) (justify left bottom) hide)
    )
    (property "Author" "Antmicro" (id 6) (at 418.465 183.515 0)
      (effects (font (size 1.27 1.27) (thickness 0.15)) (justify left bottom) hide)
    )
    (property "License" "Apache-2.0" (id 7) (at 421.005 183.515 0)
      (effects (font (size 1.27 1.27) (thickness 0.15)) (justify left bottom) hide)
    )
    (pin "1")
  )

  (symbol (lib_id "sa800u-baseboard-hw:GND") (at 398.145 201.295 0) (unit 1)
    (in_bom yes) (on_board yes) (fields_autoplaced)
    (property "Reference" "#PWR0240" (id 0) (at 398.145 207.645 0)
      (effects (font (size 1.27 1.27)) hide)
    )
    (property "Value" "GND" (id 1) (at 398.145 205.74 0))
    (property "Footprint" "" (id 2) (at 398.145 201.295 0)
      (effects (font (size 1.27 1.27)) hide)
    )
    (property "Datasheet" "" (id 3) (at 398.145 201.295 0)
      (effects (font (size 1.27 1.27)) hide)
    )
    (property "Author" "Antmicro" (id 4) (at 407.035 208.915 0)
      (effects (font (size 1.27 1.27) (thickness 0.15)) (justify left bottom) hide)
    )
    (property "License" "Apache-2.0" (id 5) (at 407.035 211.455 0)
      (effects (font (size 1.27 1.27) (thickness 0.15)) (justify left bottom) hide)
    )
    (pin "1")
  )

  (symbol (lib_id "sa800u-baseboard-hw:TP_0.75mm_SMD") (at 397.51 160.02 90) (unit 1)
    (in_bom yes) (on_board yes) (fields_autoplaced)
    (property "Reference" "TP74" (id 0) (at 400.05 156.8449 90)
      (effects (font (size 1.27 1.27)) (justify right))
    )
    (property "Value" "TP_0.75mm_SMD" (id 1) (at 397.51 160.02 0)
      (effects (font (size 1.27 1.27)) hide)
    )
    (property "Footprint" "sa800u-baseboard-hw-footprints:TP_SMD_0.75mm" (id 2) (at 397.51 160.02 0)
      (effects (font (size 1.27 1.27)) hide)
    )
    (property "Datasheet" "" (id 3) (at 397.51 160.02 0)
      (effects (font (size 1.27 1.27)) hide)
    )
    (property "MPN" "" (id 4) (at 412.75 142.24 0)
      (effects (font (size 1.27 1.27) (thickness 0.15)) (justify left bottom) hide)
    )
    (property "Manufacturer" "" (id 5) (at 415.29 142.24 0)
      (effects (font (size 1.27 1.27) (thickness 0.15)) (justify left bottom) hide)
    )
    (property "Author" "Antmicro" (id 6) (at 417.83 142.24 0)
      (effects (font (size 1.27 1.27) (thickness 0.15)) (justify left bottom) hide)
    )
    (property "License" "Apache-2.0" (id 7) (at 420.37 142.24 0)
      (effects (font (size 1.27 1.27) (thickness 0.15)) (justify left bottom) hide)
    )
    (pin "1")
  )

  (symbol (lib_id "sa800u-baseboard-hw:GND") (at 397.51 160.02 0) (unit 1)
    (in_bom yes) (on_board yes) (fields_autoplaced)
    (property "Reference" "#PWR0239" (id 0) (at 397.51 166.37 0)
      (effects (font (size 1.27 1.27)) hide)
    )
    (property "Value" "GND" (id 1) (at 397.51 165.1 0))
    (property "Footprint" "" (id 2) (at 397.51 160.02 0)
      (effects (font (size 1.27 1.27)) hide)
    )
    (property "Datasheet" "" (id 3) (at 397.51 160.02 0)
      (effects (font (size 1.27 1.27)) hide)
    )
    (property "Author" "Antmicro" (id 4) (at 406.4 167.64 0)
      (effects (font (size 1.27 1.27) (thickness 0.15)) (justify left bottom) hide)
    )
    (property "License" "Apache-2.0" (id 5) (at 406.4 170.18 0)
      (effects (font (size 1.27 1.27) (thickness 0.15)) (justify left bottom) hide)
    )
    (pin "1")
  )

  (symbol (lib_id "sa800u-baseboard-hw:TP_0.75mm_SMD") (at 56.642 95.25 90) (unit 1)
    (in_bom yes) (on_board yes) (fields_autoplaced)
    (property "Reference" "TP50" (id 0) (at 58.801 92.0749 90)
      (effects (font (size 1.27 1.27)) (justify right))
    )
    (property "Value" "TP_0.75mm_SMD" (id 1) (at 59.182 95.25 0)
      (effects (font (size 1.27 1.27)) hide)
    )
    (property "Footprint" "sa800u-baseboard-hw-footprints:TP_SMD_0.75mm" (id 2) (at 51.562 90.17 0)
      (effects (font (size 1.524 1.524)) (justify left) hide)
    )
    (property "Datasheet" "" (id 3) (at 49.022 90.17 0)
      (effects (font (size 1.524 1.524)) (justify left) hide)
    )
    (property "MPN" "" (id 4) (at 71.882 77.47 0)
      (effects (font (size 1.27 1.27) (thickness 0.15)) (justify left bottom) hide)
    )
    (property "Manufacturer" "" (id 5) (at 74.422 77.47 0)
      (effects (font (size 1.27 1.27) (thickness 0.15)) (justify left bottom) hide)
    )
    (property "Author" "Antmicro" (id 6) (at 76.962 77.47 0)
      (effects (font (size 1.27 1.27) (thickness 0.15)) (justify left bottom) hide)
    )
    (property "License" "Apache-2.0" (id 7) (at 79.502 77.47 0)
      (effects (font (size 1.27 1.27) (thickness 0.15)) (justify left bottom) hide)
    )
    (pin "1")
  )

  (symbol (lib_id "sa800u-baseboard-hw:TP_0.75mm_SMD") (at 57.531 73.66 90) (unit 1)
    (in_bom yes) (on_board yes) (fields_autoplaced)
    (property "Reference" "TP49" (id 0) (at 59.309 70.4849 90)
      (effects (font (size 1.27 1.27)) (justify right))
    )
    (property "Value" "TP_0.75mm_SMD" (id 1) (at 60.071 73.66 0)
      (effects (font (size 1.27 1.27)) hide)
    )
    (property "Footprint" "sa800u-baseboard-hw-footprints:TP_SMD_0.75mm" (id 2) (at 52.451 68.58 0)
      (effects (font (size 1.524 1.524)) (justify left) hide)
    )
    (property "Datasheet" "" (id 3) (at 49.911 68.58 0)
      (effects (font (size 1.524 1.524)) (justify left) hide)
    )
    (property "MPN" "" (id 4) (at 72.771 55.88 0)
      (effects (font (size 1.27 1.27) (thickness 0.15)) (justify left bottom) hide)
    )
    (property "Manufacturer" "" (id 5) (at 75.311 55.88 0)
      (effects (font (size 1.27 1.27) (thickness 0.15)) (justify left bottom) hide)
    )
    (property "Author" "Antmicro" (id 6) (at 77.851 55.88 0)
      (effects (font (size 1.27 1.27) (thickness 0.15)) (justify left bottom) hide)
    )
    (property "License" "Apache-2.0" (id 7) (at 80.391 55.88 0)
      (effects (font (size 1.27 1.27) (thickness 0.15)) (justify left bottom) hide)
    )
    (pin "1")
  )

  (symbol (lib_id "sa800u-baseboard-hw:TP_0.75mm_SMD") (at 57.785 53.467 90) (unit 1)
    (in_bom yes) (on_board yes) (fields_autoplaced)
    (property "Reference" "TP48" (id 0) (at 59.69 50.2919 90)
      (effects (font (size 1.27 1.27)) (justify right))
    )
    (property "Value" "TP_0.75mm_SMD" (id 1) (at 60.325 53.467 0)
      (effects (font (size 1.27 1.27)) hide)
    )
    (property "Footprint" "sa800u-baseboard-hw-footprints:TP_SMD_0.75mm" (id 2) (at 52.705 48.387 0)
      (effects (font (size 1.524 1.524)) (justify left) hide)
    )
    (property "Datasheet" "" (id 3) (at 50.165 48.387 0)
      (effects (font (size 1.524 1.524)) (justify left) hide)
    )
    (property "MPN" "" (id 4) (at 73.025 35.687 0)
      (effects (font (size 1.27 1.27) (thickness 0.15)) (justify left bottom) hide)
    )
    (property "Manufacturer" "" (id 5) (at 75.565 35.687 0)
      (effects (font (size 1.27 1.27) (thickness 0.15)) (justify left bottom) hide)
    )
    (property "Author" "Antmicro" (id 6) (at 78.105 35.687 0)
      (effects (font (size 1.27 1.27) (thickness 0.15)) (justify left bottom) hide)
    )
    (property "License" "Apache-2.0" (id 7) (at 80.645 35.687 0)
      (effects (font (size 1.27 1.27) (thickness 0.15)) (justify left bottom) hide)
    )
    (pin "1")
  )

  (symbol (lib_id "sa800u-baseboard-hw:TP_0.75mm_SMD") (at 98.933 115.57 180) (unit 1)
    (in_bom yes) (on_board yes) (fields_autoplaced)
    (property "Reference" "TP51" (id 0) (at 95.758 112.014 0))
    (property "Value" "TP_0.75mm_SMD" (id 1) (at 98.933 113.03 0)
      (effects (font (size 1.27 1.27)) hide)
    )
    (property "Footprint" "sa800u-baseboard-hw-footprints:TP_SMD_0.75mm" (id 2) (at 93.853 120.65 0)
      (effects (font (size 1.524 1.524)) (justify left) hide)
    )
    (property "Datasheet" "" (id 3) (at 93.853 123.19 0)
      (effects (font (size 1.524 1.524)) (justify left) hide)
    )
    (property "MPN" "" (id 4) (at 81.153 100.33 0)
      (effects (font (size 1.27 1.27) (thickness 0.15)) (justify left bottom) hide)
    )
    (property "Manufacturer" "" (id 5) (at 81.153 97.79 0)
      (effects (font (size 1.27 1.27) (thickness 0.15)) (justify left bottom) hide)
    )
    (property "Author" "Antmicro" (id 6) (at 81.153 95.25 0)
      (effects (font (size 1.27 1.27) (thickness 0.15)) (justify left bottom) hide)
    )
    (property "License" "Apache-2.0" (id 7) (at 81.153 92.71 0)
      (effects (font (size 1.27 1.27) (thickness 0.15)) (justify left bottom) hide)
    )
    (pin "1")
  )

  (symbol (lib_id "sa800u-baseboard-hw:TP_0.75mm_SMD") (at 111.887 115.443 180) (unit 1)
    (in_bom yes) (on_board yes) (fields_autoplaced)
    (property "Reference" "TP52" (id 0) (at 108.712 112.014 0))
    (property "Value" "TP_0.75mm_SMD" (id 1) (at 111.887 112.903 0)
      (effects (font (size 1.27 1.27)) hide)
    )
    (property "Footprint" "sa800u-baseboard-hw-footprints:TP_SMD_0.75mm" (id 2) (at 106.807 120.523 0)
      (effects (font (size 1.524 1.524)) (justify left) hide)
    )
    (property "Datasheet" "" (id 3) (at 106.807 123.063 0)
      (effects (font (size 1.524 1.524)) (justify left) hide)
    )
    (property "MPN" "" (id 4) (at 94.107 100.203 0)
      (effects (font (size 1.27 1.27) (thickness 0.15)) (justify left bottom) hide)
    )
    (property "Manufacturer" "" (id 5) (at 94.107 97.663 0)
      (effects (font (size 1.27 1.27) (thickness 0.15)) (justify left bottom) hide)
    )
    (property "Author" "Antmicro" (id 6) (at 94.107 95.123 0)
      (effects (font (size 1.27 1.27) (thickness 0.15)) (justify left bottom) hide)
    )
    (property "License" "Apache-2.0" (id 7) (at 94.107 92.583 0)
      (effects (font (size 1.27 1.27) (thickness 0.15)) (justify left bottom) hide)
    )
    (pin "1")
  )

  (symbol (lib_id "sa800u-baseboard-hw:TP_0.75mm_SMD") (at 125.095 116.713 180) (unit 1)
    (in_bom yes) (on_board yes)
    (property "Reference" "TP53" (id 0) (at 120.396 114.681 0))
    (property "Value" "TP_0.75mm_SMD" (id 1) (at 125.095 114.173 0)
      (effects (font (size 1.27 1.27)) hide)
    )
    (property "Footprint" "sa800u-baseboard-hw-footprints:TP_SMD_0.75mm" (id 2) (at 120.015 121.793 0)
      (effects (font (size 1.524 1.524)) (justify left) hide)
    )
    (property "Datasheet" "" (id 3) (at 120.015 124.333 0)
      (effects (font (size 1.524 1.524)) (justify left) hide)
    )
    (property "MPN" "" (id 4) (at 107.315 101.473 0)
      (effects (font (size 1.27 1.27) (thickness 0.15)) (justify left bottom) hide)
    )
    (property "Manufacturer" "" (id 5) (at 107.315 98.933 0)
      (effects (font (size 1.27 1.27) (thickness 0.15)) (justify left bottom) hide)
    )
    (property "Author" "Antmicro" (id 6) (at 107.315 96.393 0)
      (effects (font (size 1.27 1.27) (thickness 0.15)) (justify left bottom) hide)
    )
    (property "License" "Apache-2.0" (id 7) (at 107.315 93.853 0)
      (effects (font (size 1.27 1.27) (thickness 0.15)) (justify left bottom) hide)
    )
    (pin "1")
  )

  (symbol (lib_id "sa800u-baseboard-hw:TP_0.75mm_SMD") (at 371.094 68.072 90) (unit 1)
    (in_bom yes) (on_board yes) (fields_autoplaced)
    (property "Reference" "TP73" (id 0) (at 373.38 64.8969 90)
      (effects (font (size 1.27 1.27)) (justify right))
    )
    (property "Value" "TP_0.75mm_SMD" (id 1) (at 371.094 68.072 0)
      (effects (font (size 1.27 1.27)) hide)
    )
    (property "Footprint" "sa800u-baseboard-hw-footprints:TP_SMD_0.75mm" (id 2) (at 371.094 68.072 0)
      (effects (font (size 1.27 1.27)) hide)
    )
    (property "Datasheet" "" (id 3) (at 371.094 68.072 0)
      (effects (font (size 1.27 1.27)) hide)
    )
    (property "MPN" "" (id 4) (at 386.334 50.292 0)
      (effects (font (size 1.27 1.27) (thickness 0.15)) (justify left bottom) hide)
    )
    (property "Manufacturer" "" (id 5) (at 388.874 50.292 0)
      (effects (font (size 1.27 1.27) (thickness 0.15)) (justify left bottom) hide)
    )
    (property "Author" "Antmicro" (id 6) (at 391.414 50.292 0)
      (effects (font (size 1.27 1.27) (thickness 0.15)) (justify left bottom) hide)
    )
    (property "License" "Apache-2.0" (id 7) (at 393.954 50.292 0)
      (effects (font (size 1.27 1.27) (thickness 0.15)) (justify left bottom) hide)
    )
    (pin "1")
  )

  (symbol (lib_id "sa800u-baseboard-hw:TP_0.75mm_SMD") (at 316.357 68.199 90) (unit 1)
    (in_bom yes) (on_board yes) (fields_autoplaced)
    (property "Reference" "TP68" (id 0) (at 318.77 65.0239 90)
      (effects (font (size 1.27 1.27)) (justify right))
    )
    (property "Value" "TP_0.75mm_SMD" (id 1) (at 316.357 68.199 0)
      (effects (font (size 1.27 1.27)) hide)
    )
    (property "Footprint" "sa800u-baseboard-hw-footprints:TP_SMD_0.75mm" (id 2) (at 316.357 68.199 0)
      (effects (font (size 1.27 1.27)) hide)
    )
    (property "Datasheet" "" (id 3) (at 316.357 68.199 0)
      (effects (font (size 1.27 1.27)) hide)
    )
    (property "MPN" "" (id 4) (at 331.597 50.419 0)
      (effects (font (size 1.27 1.27) (thickness 0.15)) (justify left bottom) hide)
    )
    (property "Manufacturer" "" (id 5) (at 334.137 50.419 0)
      (effects (font (size 1.27 1.27) (thickness 0.15)) (justify left bottom) hide)
    )
    (property "Author" "Antmicro" (id 6) (at 336.677 50.419 0)
      (effects (font (size 1.27 1.27) (thickness 0.15)) (justify left bottom) hide)
    )
    (property "License" "Apache-2.0" (id 7) (at 339.217 50.419 0)
      (effects (font (size 1.27 1.27) (thickness 0.15)) (justify left bottom) hide)
    )
    (pin "1")
  )
)
